G04 ================== begin FILE IDENTIFICATION RECORD ==================*
G04 Layout Name:  15669-1.brd*
G04 Film Name:    L5VCC*
G04 File Format:  Gerber RS274X*
G04 File Origin:  Cadence Allegro 16.5-S056*
G04 Origin Date:  Wed Nov 16 04:08:50 2016*
G04 *
G04 Layer:  VIA CLASS/L5VCC*
G04 Layer:  PIN/L5VCC*
G04 Layer:  PACKAGE GEOMETRY/PWRVCC*
G04 Layer:  ETCH/L5VCC*
G04 Layer:  DRAWING FORMAT/LAYER_PCB_STORY*
G04 Layer:  DRAWING FORMAT/LAYER_L5VCC*
G04 *
G04 Offset:    (0.00 0.00)*
G04 Mirror:    No*
G04 Mode:      Negative*
G04 Rotation:  0*
G04 FullContactRelief:  No*
G04 UndefLineWidth:     6.00*
G04 ================== end FILE IDENTIFICATION RECORD ====================*
%FSLAX35Y35*MOIN*%
%IR0*IPPOS*OFA0.00000B0.00000*MIA0B0*SFA1.00000B1.00000*%
%ADD19O,.115X.072*%
%ADD11C,.03*%
%ADD15C,.032*%
%ADD17C,.036*%
%ADD13C,.099*%
%AMMACRO22*
4,1,15,.00398,.00044,
.003999,.000208,
.004004,-.000025,
.003996,-.000258,
.00398,-.00044,
.00483,-.00129,
.004897,-.001007,
.004947,-.000721,
.004981,-.000432,
.004997,-.000141,
.004997,.000149,
.00498,.00044,
.004946,.000729,
.004895,.001015,
.00483,.00129,
.00398,.00044,
90.*
4,1,15,.00044,-.00398,
.000208,-.003999,
-.000025,-.004004,
-.000258,-.003996,
-.00044,-.00398,
-.00129,-.00483,
-.001007,-.004897,
-.000721,-.004947,
-.000432,-.004981,
-.000141,-.004997,
.000149,-.004997,
.00044,-.00498,
.000729,-.004946,
.001015,-.004895,
.00129,-.00483,
.00044,-.00398,
90.*
4,1,15,-.00398,-.00044,
-.003999,-.000208,
-.004004,.000025,
-.003996,.000258,
-.00398,.00044,
-.00483,.00129,
-.004897,.001007,
-.004947,.000721,
-.004981,.000432,
-.004997,.000141,
-.004997,-.000149,
-.00498,-.00044,
-.004946,-.000729,
-.004895,-.001015,
-.00483,-.00129,
-.00398,-.00044,
90.*
4,1,15,-.00044,.00398,
-.000208,.003999,
.000025,.004004,
.000258,.003996,
.00044,.00398,
.00129,.00483,
.001007,.004897,
.000721,.004947,
.000432,.004981,
.000141,.004997,
-.000149,.004997,
-.00044,.00498,
-.000729,.004946,
-.001015,.004895,
-.00129,.00483,
-.00044,.00398,
90.*
%
%ADD22MACRO22*%
%AMMACRO18*
4,1,15,.00398,.00044,
.003999,.000208,
.004004,-.000025,
.003996,-.000258,
.00398,-.00044,
.00483,-.00129,
.004897,-.001007,
.004947,-.000721,
.004981,-.000432,
.004997,-.000141,
.004997,.000149,
.00498,.00044,
.004946,.000729,
.004895,.001015,
.00483,.00129,
.00398,.00044,
0.0*
4,1,15,.00044,-.00398,
.000208,-.003999,
-.000025,-.004004,
-.000258,-.003996,
-.00044,-.00398,
-.00129,-.00483,
-.001007,-.004897,
-.000721,-.004947,
-.000432,-.004981,
-.000141,-.004997,
.000149,-.004997,
.00044,-.00498,
.000729,-.004946,
.001015,-.004895,
.00129,-.00483,
.00044,-.00398,
0.0*
4,1,15,-.00398,-.00044,
-.003999,-.000208,
-.004004,.000025,
-.003996,.000258,
-.00398,.00044,
-.00483,.00129,
-.004897,.001007,
-.004947,.000721,
-.004981,.000432,
-.004997,.000141,
-.004997,-.000149,
-.00498,-.00044,
-.004946,-.000729,
-.004895,-.001015,
-.00483,-.00129,
-.00398,-.00044,
0.0*
4,1,15,-.00044,.00398,
-.000208,.003999,
.000025,.004004,
.000258,.003996,
.00044,.00398,
.00129,.00483,
.001007,.004897,
.000721,.004947,
.000432,.004981,
.000141,.004997,
-.000149,.004997,
-.00044,.00498,
-.000729,.004946,
-.001015,.004895,
-.00129,.00483,
-.00044,.00398,
0.0*
%
%ADD18MACRO18*%
%ADD20C,.101*%
%ADD10C,.114*%
%ADD14C,.115*%
%ADD16C,.18*%
%ADD24C,.174*%
%AMMACRO23*
4,1,15,.00398,.00044,
.003999,.000208,
.004004,-.000025,
.003996,-.000258,
.00398,-.00044,
.00483,-.00129,
.004897,-.001007,
.004947,-.000721,
.004981,-.000432,
.004997,-.000141,
.004997,.000149,
.00498,.00044,
.004946,.000729,
.004895,.001015,
.00483,.00129,
.00398,.00044,
270.*
4,1,15,.00044,-.00398,
.000208,-.003999,
-.000025,-.004004,
-.000258,-.003996,
-.00044,-.00398,
-.00129,-.00483,
-.001007,-.004897,
-.000721,-.004947,
-.000432,-.004981,
-.000141,-.004997,
.000149,-.004997,
.00044,-.00498,
.000729,-.004946,
.001015,-.004895,
.00129,-.00483,
.00044,-.00398,
270.*
4,1,15,-.00398,-.00044,
-.003999,-.000208,
-.004004,.000025,
-.003996,.000258,
-.00398,.00044,
-.00483,.00129,
-.004897,.001007,
-.004947,.000721,
-.004981,.000432,
-.004997,.000141,
-.004997,-.000149,
-.00498,-.00044,
-.004946,-.000729,
-.004895,-.001015,
-.00483,-.00129,
-.00398,-.00044,
270.*
4,1,15,-.00044,.00398,
-.000208,.003999,
.000025,.004004,
.000258,.003996,
.00044,.00398,
.00129,.00483,
.001007,.004897,
.000721,.004947,
.000432,.004981,
.000141,.004997,
-.000149,.004997,
-.00044,.00498,
-.000729,.004946,
-.001015,.004895,
-.00129,.00483,
-.00044,.00398,
270.*
%
%ADD23MACRO23*%
%AMMACRO21*
4,1,15,.00398,.00044,
.003999,.000208,
.004004,-.000025,
.003996,-.000258,
.00398,-.00044,
.00483,-.00129,
.004897,-.001007,
.004947,-.000721,
.004981,-.000432,
.004997,-.000141,
.004997,.000149,
.00498,.00044,
.004946,.000729,
.004895,.001015,
.00483,.00129,
.00398,.00044,
180.*
4,1,15,.00044,-.00398,
.000208,-.003999,
-.000025,-.004004,
-.000258,-.003996,
-.00044,-.00398,
-.00129,-.00483,
-.001007,-.004897,
-.000721,-.004947,
-.000432,-.004981,
-.000141,-.004997,
.000149,-.004997,
.00044,-.00498,
.000729,-.004946,
.001015,-.004895,
.00129,-.00483,
.00044,-.00398,
180.*
4,1,15,-.00398,-.00044,
-.003999,-.000208,
-.004004,.000025,
-.003996,.000258,
-.00398,.00044,
-.00483,.00129,
-.004897,.001007,
-.004947,.000721,
-.004981,.000432,
-.004997,.000141,
-.004997,-.000149,
-.00498,-.00044,
-.004946,-.000729,
-.004895,-.001015,
-.00483,-.00129,
-.00398,-.00044,
180.*
4,1,15,-.00044,.00398,
-.000208,.003999,
.000025,.004004,
.000258,.003996,
.00044,.00398,
.00129,.00483,
.001007,.004897,
.000721,.004947,
.000432,.004981,
.000141,.004997,
-.000149,.004997,
-.00044,.00498,
-.000729,.004946,
-.001015,.004895,
-.00129,.00483,
-.00044,.00398,
180.*
%
%ADD21MACRO21*%
%ADD25C,.02*%
%ADD26C,.006*%
%ADD32C,.09704*%
%ADD31C,.11004*%
%ADD29C,.11104*%
%ADD27O,.315X.4528*%
%ADD30C,.39404*%
%ADD28O,.315X.45279*%
G75*
%LPD*%
G75*
G36*
G01X-6000Y-6000D02*
X1043402D01*
Y1998126D01*
X-6000D01*
Y-6000D01*
G37*
%LPC*%
G75*
G36*
G01X5000Y5000D02*
Y596998D01*
X13760D01*
Y732173D01*
X14317D01*
X14352Y732017D01*
G03X18690Y732274I2148J484D01*
G03X21059Y750055I-1367J9230D01*
G02X21017Y750766I160J366D01*
G03X22012Y752501I-1017J1736D01*
G01Y755702D01*
G03X17988I-2012J0D01*
G01Y752502D01*
G03X18299Y751428I2012J1D01*
G02X17935Y750815I-338J-214D01*
G03X17323Y750835I-611J-9311D01*
G01X13760D01*
Y924002D01*
X5000D01*
Y1092998D01*
X13760D01*
Y1228236D01*
X14308D01*
X14339Y1228075D01*
G03X18696Y1228338I2161J425D01*
G03X21059Y1246118I-1373J9229D01*
G02X21017Y1246829I160J366D01*
G03X22012Y1248564I-1017J1736D01*
G01Y1251765D01*
G03X17988I-2012J0D01*
G01Y1248565D01*
G03X18299Y1247491I2012J1D01*
G02X17935Y1246878I-338J-214D01*
G03X17323Y1246898I-611J-9311D01*
G01X13760D01*
Y1420002D01*
X5000D01*
Y1510498D01*
X13760D01*
Y1645559D01*
X17323D01*
G03X17936Y1645579I2J9330D01*
G02X18301Y1644966I27J-399D01*
G03X17988Y1643890I1699J-1078D01*
G01Y1640690D01*
G03X22012Y1640689I2012J0D01*
G01Y1643890D01*
G03X21014Y1645627I-2011J0D01*
G02X21056Y1646339I202J345D01*
G03X21058Y1663439I-3734J8550D01*
G02X21016Y1664151I160J367D01*
G03X22012Y1665886I-1016J1736D01*
G01Y1669087D01*
G03X17988I-2012J0D01*
G01Y1665887D01*
G03X18299Y1664813I2012J1D01*
G02X17935Y1664200I-338J-214D01*
G03X17323Y1664220I-611J-9311D01*
G01X13760D01*
Y1838002D01*
X5000D01*
Y1987126D01*
X1032402D01*
Y1687425D01*
X1031394Y1686417D01*
X1028700D01*
G03X1028183Y1686404I5J-10472D01*
G02X1027941Y1687137I-21J400D01*
G03X1023181Y1685711I-4713J7075D01*
G02X1023382Y1684966I-2J-400D01*
G03X1018228Y1675945I5318J-9021D01*
G01Y1622091D01*
X1017220Y1621083D01*
X993681D01*
G03Y1606870I0J-7107D01*
G01X1017220D01*
X1018228Y1605862D01*
Y1434291D01*
G03X1023382Y1425270I10473J0D01*
G02X1023181Y1424525I-203J-345D01*
G03X1027941Y1423099I47J-8501D01*
G02X1028183Y1423832I221J333D01*
G03X1028700Y1423819I522J10459D01*
G01X1031394D01*
X1032402Y1422811D01*
Y5000D01*
X149608D01*
Y17717D01*
G03X118108I-15750J0D01*
G01Y5000D01*
X5000D01*
G37*
%LPD*%
G75*
G36*
G01X920858Y1860549D02*
G02X916834I-2012J0D01*
G01Y1863750D01*
G02X920858Y1863749I2012J-1D01*
G01Y1860549D01*
G37*
G36*
G01Y1455037D02*
G02X916834I-2012J0D01*
G01Y1458238D01*
G02X920858Y1458237I2012J-1D01*
G01Y1455037D01*
G37*
G36*
G01Y1049525D02*
G02X916834I-2012J0D01*
G01Y1052726D01*
G02X920858Y1052725I2012J-1D01*
G01Y1049525D01*
G37*
G36*
G01Y644013D02*
G02X916834I-2012J0D01*
G01Y647214D01*
G02X920858Y647213I2012J-1D01*
G01Y644013D01*
G37*
G36*
G01Y238501D02*
G02X916834I-2012J0D01*
G01Y241702D01*
G02X920858Y241701I2012J-1D01*
G01Y238501D01*
G37*
G36*
G01X865430Y1909435D02*
G02X869452I2011J0D01*
G01Y1906234D01*
G02X865430Y1906235I-2011J1D01*
G01Y1909435D01*
G37*
G36*
G01Y1890538D02*
G02X869452I2011J0D01*
G01Y1887337D01*
G02X865430Y1887338I-2011J1D01*
G01Y1890538D01*
G37*
G36*
G01X870530Y1919484D02*
G02X875352I2411J0D01*
G01Y1915083D01*
G02X870530Y1915084I-2411J1D01*
G01Y1919484D01*
G37*
G36*
G01Y1900586D02*
G02X875352I2411J0D01*
G01Y1896185D01*
G02X870530Y1896186I-2411J1D01*
G01Y1900586D01*
G37*
G36*
G01X865430Y1928333D02*
G02X869452I2011J0D01*
G01Y1925132D01*
G02X865430Y1925133I-2011J1D01*
G01Y1928333D01*
G37*
G36*
G01X870530Y1938382D02*
G02X875352I2411J0D01*
G01Y1933981D01*
G02X870530Y1933982I-2411J1D01*
G01Y1938382D01*
G37*
G36*
G01X865430Y1840144D02*
G02X869452I2011J0D01*
G01Y1836943D01*
G02X865430Y1836944I-2011J1D01*
G01Y1840144D01*
G37*
G36*
G01X870530Y1850193D02*
G02X875352I2411J0D01*
G01Y1845792D01*
G02X870530Y1845793I-2411J1D01*
G01Y1850193D01*
G37*
G36*
G01X905146Y1855430D02*
G02Y1859454I0J2012D01*
G01X908347D01*
G02X908346Y1855430I-1J-2012D01*
G01X905146D01*
G37*
G36*
G01X865430Y1522821D02*
G02X869452I2011J0D01*
G01Y1519620D01*
G02X865430Y1519621I-2011J1D01*
G01Y1522821D01*
G37*
G36*
G01X870530Y1532870D02*
G02X875352I2411J0D01*
G01Y1528469D01*
G02X870530Y1528470I-2411J1D01*
G01Y1532870D01*
G37*
G36*
G01Y1513972D02*
G02X875352I2411J0D01*
G01Y1509571D01*
G02X870530Y1509572I-2411J1D01*
G01Y1513972D01*
G37*
G36*
G01X865430Y1485026D02*
G02X869452I2011J0D01*
G01Y1481825D01*
G02X865430Y1481826I-2011J1D01*
G01Y1485026D01*
G37*
G36*
G01X870530Y1444681D02*
G02X875352I2411J0D01*
G01Y1440280D01*
G02X870530Y1440281I-2411J1D01*
G01Y1444681D01*
G37*
G36*
G01X865430Y1503923D02*
G02X869452I2011J0D01*
G01Y1500722D01*
G02X865430Y1500723I-2011J1D01*
G01Y1503923D01*
G37*
G36*
G01X870530Y1495074D02*
G02X875352I2411J0D01*
G01Y1490673D01*
G02X870530Y1490674I-2411J1D01*
G01Y1495074D01*
G37*
G36*
G01X905146Y1449918D02*
G02Y1453942I0J2012D01*
G01X908347D01*
G02X908346Y1449918I-1J-2012D01*
G01X905146D01*
G37*
G36*
G01X865430Y1434632D02*
G02X869452I2011J0D01*
G01Y1431431D01*
G02X865430Y1431432I-2011J1D01*
G01Y1434632D01*
G37*
G36*
G01Y1098411D02*
G02X869452I2011J0D01*
G01Y1095210D01*
G02X865430Y1095211I-2011J1D01*
G01Y1098411D01*
G37*
G36*
G01Y1117309D02*
G02X869452I2011J0D01*
G01Y1114108D01*
G02X865430Y1114109I-2011J1D01*
G01Y1117309D01*
G37*
G36*
G01X870530Y1108460D02*
G02X875352I2411J0D01*
G01Y1104059D01*
G02X870530Y1104060I-2411J1D01*
G01Y1108460D01*
G37*
G36*
G01Y1089562D02*
G02X875352I2411J0D01*
G01Y1085161D01*
G02X870530Y1085162I-2411J1D01*
G01Y1089562D01*
G37*
G36*
G01X865430Y1079514D02*
G02X869452I2011J0D01*
G01Y1076313D01*
G02X865430Y1076314I-2011J1D01*
G01Y1079514D01*
G37*
G36*
G01X870530Y1127358D02*
G02X875352I2411J0D01*
G01Y1122957D01*
G02X870530Y1122958I-2411J1D01*
G01Y1127358D01*
G37*
G36*
G01X865430Y1029120D02*
G02X869452I2011J0D01*
G01Y1025919D01*
G02X865430Y1025920I-2011J1D01*
G01Y1029120D01*
G37*
G36*
G01X870530Y1039169D02*
G02X875352I2411J0D01*
G01Y1034768D01*
G02X870530Y1034769I-2411J1D01*
G01Y1039169D01*
G37*
G36*
G01X905146Y1044406D02*
G02Y1048430I0J2012D01*
G01X908347D01*
G02X908346Y1044406I-1J-2012D01*
G01X905146D01*
G37*
G36*
G01X865430Y711797D02*
G02X869452I2011J0D01*
G01Y708596D01*
G02X865430Y708597I-2011J1D01*
G01Y711797D01*
G37*
G36*
G01X870530Y721846D02*
G02X875352I2411J0D01*
G01Y717445D01*
G02X870530Y717446I-2411J1D01*
G01Y721846D01*
G37*
G36*
G01X865430Y674002D02*
G02X869452I2011J0D01*
G01Y670801D01*
G02X865430Y670802I-2011J1D01*
G01Y674002D01*
G37*
G36*
G01X870530Y684050D02*
G02X875352I2411J0D01*
G01Y679649D01*
G02X870530Y679650I-2411J1D01*
G01Y684050D01*
G37*
G36*
G01X865430Y692899D02*
G02X869452I2011J0D01*
G01Y689698D01*
G02X865430Y689699I-2011J1D01*
G01Y692899D01*
G37*
G36*
G01X870530Y702948D02*
G02X875352I2411J0D01*
G01Y698547D01*
G02X870530Y698548I-2411J1D01*
G01Y702948D01*
G37*
G36*
G01X905146Y638894D02*
G02Y642918I0J2012D01*
G01X908347D01*
G02X908346Y638894I-1J-2012D01*
G01X905146D01*
G37*
G36*
G01X865430Y623608D02*
G02X869452I2011J0D01*
G01Y620407D01*
G02X865430Y620408I-2011J1D01*
G01Y623608D01*
G37*
G36*
G01X870530Y633657D02*
G02X875352I2411J0D01*
G01Y629256D01*
G02X870530Y629257I-2411J1D01*
G01Y633657D01*
G37*
G36*
G01X865430Y287387D02*
G02X869452I2011J0D01*
G01Y284186D01*
G02X865430Y284187I-2011J1D01*
G01Y287387D01*
G37*
G36*
G01Y306285D02*
G02X869452I2011J0D01*
G01Y303084D01*
G02X865430Y303085I-2011J1D01*
G01Y306285D01*
G37*
G36*
G01X870530Y316334D02*
G02X875352I2411J0D01*
G01Y311933D01*
G02X870530Y311934I-2411J1D01*
G01Y316334D01*
G37*
G36*
G01Y297436D02*
G02X875352I2411J0D01*
G01Y293035D01*
G02X870530Y293036I-2411J1D01*
G01Y297436D01*
G37*
G36*
G01Y278538D02*
G02X875352I2411J0D01*
G01Y274137D01*
G02X870530Y274138I-2411J1D01*
G01Y278538D01*
G37*
G36*
G01X865430Y218096D02*
G02X869452I2011J0D01*
G01Y214895D01*
G02X865430Y214896I-2011J1D01*
G01Y218096D01*
G37*
G36*
G01X870530Y228145D02*
G02X875352I2411J0D01*
G01Y223744D01*
G02X870530Y223745I-2411J1D01*
G01Y228145D01*
G37*
G36*
G01X865430Y268490D02*
G02X869452I2011J0D01*
G01Y265289D01*
G02X865430Y265290I-2011J1D01*
G01Y268490D01*
G37*
G36*
G01X905146Y233382D02*
G02Y237406I0J2012D01*
G01X908347D01*
G02X908346Y233382I-1J-2012D01*
G01X905146D01*
G37*
G36*
G01X259842Y1889754D02*
Y1903534D01*
G02X291340I15749J0D01*
G01Y1889754D01*
G02X259842I-15749J0D01*
G37*
G36*
G01X295600Y1695412D02*
G02Y1691388I0J-2012D01*
G01X292399D01*
G02X292400Y1695412I1J2012D01*
G01X295600D01*
G37*
G36*
G01X282988Y1700600D02*
G02X287012I2012J0D01*
G01Y1697399D01*
G02X282988Y1697400I-2012J1D01*
G01Y1700600D01*
G37*
G36*
G01X259842Y1074793D02*
Y1088573D01*
G02X291340I15749J0D01*
G01Y1074793D01*
G02X259842I-15749J0D01*
G37*
G36*
G01Y671250D02*
Y685030D01*
G02X291340I15749J0D01*
G01Y671250D01*
G02X259842I-15749J0D01*
G37*
G36*
G01Y265748D02*
Y279528D01*
G02X291340I15749J0D01*
G01Y265748D01*
G02X259842I-15749J0D01*
G37*
G36*
G01X188488Y1863749D02*
G02X192512I2012J0D01*
G01Y1860548D01*
G02X188488Y1860549I-2012J1D01*
G01Y1863749D01*
G37*
G36*
G01Y1458237D02*
G02X192512I2012J0D01*
G01Y1455036D01*
G02X188488Y1455037I-2012J1D01*
G01Y1458237D01*
G37*
G36*
G01Y1052725D02*
G02X192512I2012J0D01*
G01Y1049524D01*
G02X188488Y1049525I-2012J1D01*
G01Y1052725D01*
G37*
G36*
G01Y647213D02*
G02X192512I2012J0D01*
G01Y644012D01*
G02X188488Y644013I-2012J1D01*
G01Y647213D01*
G37*
G36*
G01Y241701D02*
G02X192512I2012J0D01*
G01Y238500D01*
G02X188488Y238501I-2012J1D01*
G01Y241701D01*
G37*
G36*
G01X141106Y1925133D02*
G02X137084I-2011J0D01*
G01Y1928334D01*
G02X141106Y1928333I2011J-1D01*
G01Y1925133D01*
G37*
G36*
G01Y1906235D02*
G02X137084I-2011J0D01*
G01Y1909436D01*
G02X141106Y1909435I2011J-1D01*
G01Y1906235D01*
G37*
G36*
G01Y1887338D02*
G02X137084I-2011J0D01*
G01Y1890539D01*
G02X141106Y1890538I2011J-1D01*
G01Y1887338D01*
G37*
G36*
G01X147006Y1933982D02*
G02X142184I-2411J0D01*
G01Y1938383D01*
G02X147006Y1938382I2411J-1D01*
G01Y1933982D01*
G37*
G36*
G01X142184Y1919484D02*
G02X147006I2411J0D01*
G01Y1915083D01*
G02X142184Y1915084I-2411J1D01*
G01Y1919484D01*
G37*
G36*
G01X147006Y1896186D02*
G02X142184I-2411J0D01*
G01Y1900587D01*
G02X147006Y1900586I2411J-1D01*
G01Y1896186D01*
G37*
G36*
G01X176800Y1855430D02*
G02Y1859454I0J2012D01*
G01X180001D01*
G02X180000Y1855430I-1J-2012D01*
G01X176800D01*
G37*
G36*
G01X141106Y1836944D02*
G02X137084I-2011J0D01*
G01Y1840145D01*
G02X141106Y1840144I2011J-1D01*
G01Y1836944D01*
G37*
G36*
G01X147006Y1845793D02*
G02X142184I-2411J0D01*
G01Y1850194D01*
G02X147006Y1850193I2411J-1D01*
G01Y1845793D01*
G37*
G36*
G01X122988Y1753534D02*
G02X127012I2012J0D01*
G01Y1750333D01*
G02X122988Y1750334I-2012J1D01*
G01Y1753534D01*
G37*
G36*
G01X137084Y1522821D02*
G02X141106I2011J0D01*
G01Y1519620D01*
G02X137084Y1519621I-2011J1D01*
G01Y1522821D01*
G37*
G36*
G01X142184Y1513972D02*
G02X147006I2411J0D01*
G01Y1509571D01*
G02X142184Y1509572I-2411J1D01*
G01Y1513972D01*
G37*
G36*
G01Y1532870D02*
G02X147006I2411J0D01*
G01Y1528469D01*
G02X142184Y1528470I-2411J1D01*
G01Y1532870D01*
G37*
G36*
G01X180000Y1453942D02*
G02Y1449918I0J-2012D01*
G01X176799D01*
G02X176800Y1453942I1J2012D01*
G01X180000D01*
G37*
G36*
G01X137084Y1503923D02*
G02X141106I2011J0D01*
G01Y1500722D01*
G02X137084Y1500723I-2011J1D01*
G01Y1503923D01*
G37*
G36*
G01Y1485026D02*
G02X141106I2011J0D01*
G01Y1481825D01*
G02X137084Y1481826I-2011J1D01*
G01Y1485026D01*
G37*
G36*
G01X142184Y1495074D02*
G02X147006I2411J0D01*
G01Y1490673D01*
G02X142184Y1490674I-2411J1D01*
G01Y1495074D01*
G37*
G36*
G01Y1444681D02*
G02X147006I2411J0D01*
G01Y1440280D01*
G02X142184Y1440281I-2411J1D01*
G01Y1444681D01*
G37*
G36*
G01X137084Y1434632D02*
G02X141106I2011J0D01*
G01Y1431431D01*
G02X137084Y1431432I-2011J1D01*
G01Y1434632D01*
G37*
G36*
G01X127488Y1348021D02*
G02X131512I2012J0D01*
G01Y1344820D01*
G02X127488Y1344821I-2012J1D01*
G01Y1348021D01*
G37*
G36*
G01X137084Y1117309D02*
G02X141106I2011J0D01*
G01Y1114108D01*
G02X137084Y1114109I-2011J1D01*
G01Y1117309D01*
G37*
G36*
G01Y1098411D02*
G02X141106I2011J0D01*
G01Y1095210D01*
G02X137084Y1095211I-2011J1D01*
G01Y1098411D01*
G37*
G36*
G01Y1079514D02*
G02X141106I2011J0D01*
G01Y1076313D01*
G02X137084Y1076314I-2011J1D01*
G01Y1079514D01*
G37*
G36*
G01X142184Y1089562D02*
G02X147006I2411J0D01*
G01Y1085161D01*
G02X142184Y1085162I-2411J1D01*
G01Y1089562D01*
G37*
G36*
G01Y1108460D02*
G02X147006I2411J0D01*
G01Y1104059D01*
G02X142184Y1104060I-2411J1D01*
G01Y1108460D01*
G37*
G36*
G01Y1127358D02*
G02X147006I2411J0D01*
G01Y1122957D01*
G02X142184Y1122958I-2411J1D01*
G01Y1127358D01*
G37*
G36*
G01X180000Y1048430D02*
G02Y1044406I0J-2012D01*
G01X176799D01*
G02X176800Y1048430I1J2012D01*
G01X180000D01*
G37*
G36*
G01X137084Y1029120D02*
G02X141106I2011J0D01*
G01Y1025919D01*
G02X137084Y1025920I-2011J1D01*
G01Y1029120D01*
G37*
G36*
G01X142184Y1039169D02*
G02X147006I2411J0D01*
G01Y1034768D01*
G02X142184Y1034769I-2411J1D01*
G01Y1039169D01*
G37*
G36*
G01X164988Y942509D02*
G02X169012I2012J0D01*
G01Y939308D01*
G02X164988Y939309I-2012J1D01*
G01Y942509D01*
G37*
G36*
G01X137084Y711797D02*
G02X141106I2011J0D01*
G01Y708596D01*
G02X137084Y708597I-2011J1D01*
G01Y711797D01*
G37*
G36*
G01X142184Y721846D02*
G02X147006I2411J0D01*
G01Y717445D01*
G02X142184Y717446I-2411J1D01*
G01Y721846D01*
G37*
G36*
G01X180000Y642918D02*
G02Y638894I0J-2012D01*
G01X176799D01*
G02X176800Y642918I1J2012D01*
G01X180000D01*
G37*
G36*
G01X137084Y692899D02*
G02X141106I2011J0D01*
G01Y689698D01*
G02X137084Y689699I-2011J1D01*
G01Y692899D01*
G37*
G36*
G01Y674002D02*
G02X141106I2011J0D01*
G01Y670801D01*
G02X137084Y670802I-2011J1D01*
G01Y674002D01*
G37*
G36*
G01X142184Y702948D02*
G02X147006I2411J0D01*
G01Y698547D01*
G02X142184Y698548I-2411J1D01*
G01Y702948D01*
G37*
G36*
G01Y684050D02*
G02X147006I2411J0D01*
G01Y679649D01*
G02X142184Y679650I-2411J1D01*
G01Y684050D01*
G37*
G36*
G01X137084Y623608D02*
G02X141106I2011J0D01*
G01Y620407D01*
G02X137084Y620408I-2011J1D01*
G01Y623608D01*
G37*
G36*
G01X142184Y633657D02*
G02X147006I2411J0D01*
G01Y629256D01*
G02X142184Y629257I-2411J1D01*
G01Y633657D01*
G37*
G36*
G01X121988Y537073D02*
G02X126012I2012J0D01*
G01Y533872D01*
G02X121988Y533873I-2012J1D01*
G01Y537073D01*
G37*
G36*
G01X137084Y306285D02*
G02X141106I2011J0D01*
G01Y303084D01*
G02X137084Y303085I-2011J1D01*
G01Y306285D01*
G37*
G36*
G01Y287387D02*
G02X141106I2011J0D01*
G01Y284186D01*
G02X137084Y284187I-2011J1D01*
G01Y287387D01*
G37*
G36*
G01X142184Y278538D02*
G02X147006I2411J0D01*
G01Y274137D01*
G02X142184Y274138I-2411J1D01*
G01Y278538D01*
G37*
G36*
G01Y297436D02*
G02X147006I2411J0D01*
G01Y293035D01*
G02X142184Y293036I-2411J1D01*
G01Y297436D01*
G37*
G36*
G01Y316334D02*
G02X147006I2411J0D01*
G01Y311933D01*
G02X142184Y311934I-2411J1D01*
G01Y316334D01*
G37*
G36*
G01X180000Y237406D02*
G02Y233382I0J-2012D01*
G01X176799D01*
G02X176800Y237406I1J2012D01*
G01X180000D01*
G37*
G36*
G01X137084Y268490D02*
G02X141106I2011J0D01*
G01Y265289D01*
G02X137084Y265290I-2011J1D01*
G01Y268490D01*
G37*
G36*
G01Y218096D02*
G02X141106I2011J0D01*
G01Y214895D01*
G02X137084Y214896I-2011J1D01*
G01Y218096D01*
G37*
G36*
G01X142184Y228145D02*
G02X147006I2411J0D01*
G01Y223744D01*
G02X142184Y223745I-2411J1D01*
G01Y228145D01*
G37*
G36*
G01X121988Y131559D02*
G02X126012I2012J0D01*
G01Y128358D01*
G02X121988Y128359I-2012J1D01*
G01Y131559D01*
G37*
G36*
G01X97088Y1768381D02*
G02X101912I2412J0D01*
G01Y1763980D01*
G02X97088Y1763981I-2412J1D01*
G01Y1768381D01*
G37*
G36*
G01X102988Y1726836D02*
G02X107012I2012J0D01*
G01Y1723635D01*
G02X102988Y1723636I-2012J1D01*
G01Y1726836D01*
G37*
G36*
G01Y1777230D02*
G02X107012I2012J0D01*
G01Y1774029D01*
G02X102988Y1774030I-2012J1D01*
G01Y1777230D01*
G37*
G36*
G01X70012Y1750407D02*
G02X65988I-2012J0D01*
G01Y1753608D01*
G02X70012Y1753607I2012J-1D01*
G01Y1750407D01*
G37*
G36*
G01X97088Y1699090D02*
G02X101912I2412J0D01*
G01Y1694689D01*
G02X97088Y1694690I-2412J1D01*
G01Y1699090D01*
G37*
G36*
G01Y1680192D02*
G02X101912I2412J0D01*
G01Y1675791D01*
G02X97088Y1675792I-2412J1D01*
G01Y1680192D01*
G37*
G36*
G01X102988Y1707939D02*
G02X107012I2012J0D01*
G01Y1704738D01*
G02X102988Y1704739I-2012J1D01*
G01Y1707939D01*
G37*
G36*
G01Y1689041D02*
G02X107012I2012J0D01*
G01Y1685840D01*
G02X102988Y1685841I-2012J1D01*
G01Y1689041D01*
G37*
G36*
G01X97088Y1717988D02*
G02X101912I2412J0D01*
G01Y1713587D01*
G02X97088Y1713588I-2412J1D01*
G01Y1717988D01*
G37*
G36*
G01X107012Y1368518D02*
G02X102988I-2012J0D01*
G01Y1371719D01*
G02X107012Y1371718I2012J-1D01*
G01Y1368518D01*
G37*
G36*
G01X101912Y1289178D02*
G02X97088I-2412J0D01*
G01Y1293579D01*
G02X101912Y1293578I2412J-1D01*
G01Y1289178D01*
G37*
G36*
G01X97088Y1362869D02*
G02X101912I2412J0D01*
G01Y1358468D01*
G02X97088Y1358469I-2412J1D01*
G01Y1362869D01*
G37*
G36*
G01X101912Y1308076D02*
G02X97088I-2412J0D01*
G01Y1312477D01*
G02X101912Y1312476I2412J-1D01*
G01Y1308076D01*
G37*
G36*
G01X70012Y1344895D02*
G02X65988I-2012J0D01*
G01Y1348096D01*
G02X70012Y1348095I2012J-1D01*
G01Y1344895D01*
G37*
G36*
G01X107012Y1318124D02*
G02X102988I-2012J0D01*
G01Y1321325D01*
G02X107012Y1321324I2012J-1D01*
G01Y1318124D01*
G37*
G36*
G01Y1299227D02*
G02X102988I-2012J0D01*
G01Y1302428D01*
G02X107012Y1302427I2012J-1D01*
G01Y1299227D01*
G37*
G36*
G01X101912Y1270280D02*
G02X97088I-2412J0D01*
G01Y1274681D01*
G02X101912Y1274680I2412J-1D01*
G01Y1270280D01*
G37*
G36*
G01X107012Y1280329D02*
G02X102988I-2012J0D01*
G01Y1283530D01*
G02X107012Y1283529I2012J-1D01*
G01Y1280329D01*
G37*
G36*
G01X70012Y939383D02*
G02X65988I-2012J0D01*
G01Y942584D01*
G02X70012Y942583I2012J-1D01*
G01Y939383D01*
G37*
G36*
G01X107012Y963006D02*
G02X102988I-2012J0D01*
G01Y966207D01*
G02X107012Y966206I2012J-1D01*
G01Y963006D01*
G37*
G36*
G01X101912Y952957D02*
G02X97088I-2412J0D01*
G01Y957358D01*
G02X101912Y957357I2412J-1D01*
G01Y952957D01*
G37*
G36*
G01X97088Y869168D02*
G02X101912I2412J0D01*
G01Y864767D01*
G02X97088Y864768I-2412J1D01*
G01Y869168D01*
G37*
G36*
G01X107012Y912612D02*
G02X102988I-2012J0D01*
G01Y915813D01*
G02X107012Y915812I2012J-1D01*
G01Y912612D01*
G37*
G36*
G01Y893715D02*
G02X102988I-2012J0D01*
G01Y896916D01*
G02X107012Y896915I2012J-1D01*
G01Y893715D01*
G37*
G36*
G01Y874817D02*
G02X102988I-2012J0D01*
G01Y878018D01*
G02X107012Y878017I2012J-1D01*
G01Y874817D01*
G37*
G36*
G01X101912Y902564D02*
G02X97088I-2412J0D01*
G01Y906965D01*
G02X101912Y906964I2412J-1D01*
G01Y902564D01*
G37*
G36*
G01Y883666D02*
G02X97088I-2412J0D01*
G01Y888067D01*
G02X101912Y888066I2412J-1D01*
G01Y883666D01*
G37*
G36*
G01X97088Y551845D02*
G02X101912I2412J0D01*
G01Y547444D01*
G02X97088Y547445I-2412J1D01*
G01Y551845D01*
G37*
G36*
G01X70012Y533871D02*
G02X65988I-2012J0D01*
G01Y537072D01*
G02X70012Y537071I2012J-1D01*
G01Y533871D01*
G37*
G36*
G01X107012Y507100D02*
G02X102988I-2012J0D01*
G01Y510301D01*
G02X107012Y510300I2012J-1D01*
G01Y507100D01*
G37*
G36*
G01Y557494D02*
G02X102988I-2012J0D01*
G01Y560695D01*
G02X107012Y560694I2012J-1D01*
G01Y557494D01*
G37*
G36*
G01Y488203D02*
G02X102988I-2012J0D01*
G01Y491404D01*
G02X107012Y491403I2012J-1D01*
G01Y488203D01*
G37*
G36*
G01X101912Y497052D02*
G02X97088I-2412J0D01*
G01Y501453D01*
G02X101912Y501452I2412J-1D01*
G01Y497052D01*
G37*
G36*
G01X107012Y469305D02*
G02X102988I-2012J0D01*
G01Y472506D01*
G02X107012Y472505I2012J-1D01*
G01Y469305D01*
G37*
G36*
G01X97088Y463656D02*
G02X101912I2412J0D01*
G01Y459255D01*
G02X97088Y459256I-2412J1D01*
G01Y463656D01*
G37*
G36*
G01X101912Y478154D02*
G02X97088I-2412J0D01*
G01Y482555D01*
G02X101912Y482554I2412J-1D01*
G01Y478154D01*
G37*
G36*
G01X65988Y131559D02*
G02X70012I2012J0D01*
G01Y128358D01*
G02X65988Y128359I-2012J1D01*
G01Y131559D01*
G37*
G36*
G01X107012Y151982D02*
G02X102988I-2012J0D01*
G01Y155183D01*
G02X107012Y155182I2012J-1D01*
G01Y151982D01*
G37*
G36*
G01X101912Y141933D02*
G02X97088I-2412J0D01*
G01Y146334D01*
G02X101912Y146333I2412J-1D01*
G01Y141933D01*
G37*
G36*
G01Y72642D02*
G02X97088I-2412J0D01*
G01Y77043D01*
G02X101912Y77042I2412J-1D01*
G01Y72642D01*
G37*
G36*
G01X97088Y58244D02*
G02X101912I2412J0D01*
G01Y53843D01*
G02X97088Y53844I-2412J1D01*
G01Y58244D01*
G37*
G36*
G01X107012Y101588D02*
G02X102988I-2012J0D01*
G01Y104789D01*
G02X107012Y104788I2012J-1D01*
G01Y101588D01*
G37*
G36*
G01Y82691D02*
G02X102988I-2012J0D01*
G01Y85892D01*
G02X107012Y85891I2012J-1D01*
G01Y82691D01*
G37*
G36*
G01Y63793D02*
G02X102988I-2012J0D01*
G01Y66994D01*
G02X107012Y66993I2012J-1D01*
G01Y63793D01*
G37*
G36*
G01X101912Y91540D02*
G02X97088I-2412J0D01*
G01Y95941D01*
G02X101912Y95940I2412J-1D01*
G01Y91540D01*
G37*
G36*
G01X5904Y1909055D02*
Y1922835D01*
G02X37404I15750J0D01*
G01Y1909055D01*
G02X5904I-15750J0D01*
G37*
G36*
G01X28700Y1771570D02*
G02Y1767546I0J-2012D01*
G01X25499D01*
G02X25500Y1771570I1J2012D01*
G01X28700D01*
G37*
G36*
G01X29540Y1732221D02*
G02X25518I-2011J0D01*
G01Y1735422D01*
G02X29540Y1735421I2011J-1D01*
G01Y1732221D01*
G37*
G36*
G01Y1744820D02*
G02X25518I-2011J0D01*
G01Y1748021D01*
G02X29540Y1748020I2011J-1D01*
G01Y1744820D01*
G37*
G36*
G01Y1757418D02*
G02X25518I-2011J0D01*
G01Y1760619D01*
G02X29540Y1760618I2011J-1D01*
G01Y1757418D01*
G37*
G36*
G01X22012Y1725729D02*
G02X17988I-2012J0D01*
G01Y1728930D01*
G02X22012Y1728929I2012J-1D01*
G01Y1725729D01*
G37*
G36*
G01Y1738328D02*
G02X17988I-2012J0D01*
G01Y1741529D01*
G02X22012Y1741528I2012J-1D01*
G01Y1738328D01*
G37*
G36*
G01Y1750926D02*
G02X17988I-2012J0D01*
G01Y1754127D01*
G02X22012Y1754126I2012J-1D01*
G01Y1750926D01*
G37*
G36*
G01X25518Y1688177D02*
G02X29540I2011J0D01*
G01Y1684976D01*
G02X25518Y1684977I-2011J1D01*
G01Y1688177D01*
G37*
G36*
G01Y1700776D02*
G02X29540I2011J0D01*
G01Y1697575D01*
G02X25518Y1697576I-2011J1D01*
G01Y1700776D01*
G37*
G36*
G01Y1675579D02*
G02X29540I2011J0D01*
G01Y1672378D01*
G02X25518Y1672379I-2011J1D01*
G01Y1675579D01*
G37*
G36*
G01X29540Y1719623D02*
G02X25518I-2011J0D01*
G01Y1722824D01*
G02X29540Y1722823I2011J-1D01*
G01Y1719623D01*
G37*
G36*
G01X17988Y1681685D02*
G02X22012I2012J0D01*
G01Y1678484D01*
G02X17988Y1678485I-2012J1D01*
G01Y1681685D01*
G37*
G36*
G01Y1694283D02*
G02X22012I2012J0D01*
G01Y1691082D01*
G02X17988Y1691083I-2012J1D01*
G01Y1694283D01*
G37*
G36*
G01X22012Y1713131D02*
G02X17988I-2012J0D01*
G01Y1716332D01*
G02X22012Y1716331I2012J-1D01*
G01Y1713131D01*
G37*
G36*
G01X29540Y1583999D02*
G02X25518I-2011J0D01*
G01Y1587200D01*
G02X29540Y1587199I2011J-1D01*
G01Y1583999D01*
G37*
G36*
G01Y1596597D02*
G02X25518I-2011J0D01*
G01Y1599798D01*
G02X29540Y1599797I2011J-1D01*
G01Y1596597D01*
G37*
G36*
G01Y1609196D02*
G02X25518I-2011J0D01*
G01Y1612397D01*
G02X29540Y1612396I2011J-1D01*
G01Y1609196D01*
G37*
G36*
G01Y1621794D02*
G02X25518I-2011J0D01*
G01Y1624995D01*
G02X29540Y1624994I2011J-1D01*
G01Y1621794D01*
G37*
G36*
G01X25518Y1637593D02*
G02X29540I2011J0D01*
G01Y1634392D01*
G02X25518Y1634393I-2011J1D01*
G01Y1637593D01*
G37*
G36*
G01X22012Y1590296D02*
G02X17988I-2012J0D01*
G01Y1593497D01*
G02X22012Y1593496I2012J-1D01*
G01Y1590296D01*
G37*
G36*
G01Y1602894D02*
G02X17988I-2012J0D01*
G01Y1606095D01*
G02X22012Y1606094I2012J-1D01*
G01Y1602894D01*
G37*
G36*
G01Y1615493D02*
G02X17988I-2012J0D01*
G01Y1618694D01*
G02X22012Y1618693I2012J-1D01*
G01Y1615493D01*
G37*
G36*
G01Y1628091D02*
G02X17988I-2012J0D01*
G01Y1631292D01*
G02X22012Y1631291I2012J-1D01*
G01Y1628091D01*
G37*
G36*
G01X33001Y1516112D02*
G02Y1520134I0J2011D01*
G01X36202D01*
G02X36201Y1516112I-1J-2011D01*
G01X33001D01*
G37*
G36*
G01X25518Y1527356D02*
G02X29540I2011J0D01*
G01Y1524155D01*
G02X25518Y1524156I-2011J1D01*
G01Y1527356D01*
G37*
G36*
G01Y1539955D02*
G02X29540I2011J0D01*
G01Y1536754D01*
G02X25518Y1536755I-2011J1D01*
G01Y1539955D01*
G37*
G36*
G01Y1552553D02*
G02X29540I2011J0D01*
G01Y1549352D01*
G02X25518Y1549353I-2011J1D01*
G01Y1552553D01*
G37*
G36*
G01Y1565152D02*
G02X29540I2011J0D01*
G01Y1561951D01*
G02X25518Y1561952I-2011J1D01*
G01Y1565152D01*
G37*
G36*
G01X17988Y1533654D02*
G02X22012I2012J0D01*
G01Y1530453D01*
G02X17988Y1530454I-2012J1D01*
G01Y1533654D01*
G37*
G36*
G01Y1546252D02*
G02X22012I2012J0D01*
G01Y1543051D01*
G02X17988Y1543052I-2012J1D01*
G01Y1546252D01*
G37*
G36*
G01Y1558850D02*
G02X22012I2012J0D01*
G01Y1555649D01*
G02X17988Y1555650I-2012J1D01*
G01Y1558850D01*
G37*
G36*
G01Y1571449D02*
G02X22012I2012J0D01*
G01Y1568248D01*
G02X17988Y1568249I-2012J1D01*
G01Y1571449D01*
G37*
G36*
G01X29540Y1365102D02*
G02X25518I-2011J0D01*
G01Y1368303D01*
G02X29540Y1368302I2011J-1D01*
G01Y1365102D01*
G37*
G36*
G01Y1377700D02*
G02X25518I-2011J0D01*
G01Y1380901D01*
G02X29540Y1380900I2011J-1D01*
G01Y1377700D01*
G37*
G36*
G01X25518Y1393499D02*
G02X29540I2011J0D01*
G01Y1390298D01*
G02X25518Y1390299I-2011J1D01*
G01Y1393499D01*
G37*
G36*
G01X29540Y1402897D02*
G02X25518I-2011J0D01*
G01Y1406098D01*
G02X29540Y1406097I2011J-1D01*
G01Y1402897D01*
G37*
G36*
G01X17988Y1374599D02*
G02X22012I2012J0D01*
G01Y1371398D01*
G02X17988Y1371399I-2012J1D01*
G01Y1374599D01*
G37*
G36*
G01Y1387198D02*
G02X22012I2012J0D01*
G01Y1383997D01*
G02X17988Y1383998I-2012J1D01*
G01Y1387198D01*
G37*
G36*
G01Y1399796D02*
G02X22012I2012J0D01*
G01Y1396595D01*
G02X17988Y1396596I-2012J1D01*
G01Y1399796D01*
G37*
G36*
G01Y1412395D02*
G02X22012I2012J0D01*
G01Y1409194D01*
G02X17988Y1409195I-2012J1D01*
G01Y1412395D01*
G37*
G36*
G01X29540Y1292661D02*
G02X25518I-2011J0D01*
G01Y1295862D01*
G02X29540Y1295861I2011J-1D01*
G01Y1292661D01*
G37*
G36*
G01X25518Y1318108D02*
G02X29540I2011J0D01*
G01Y1314907D01*
G02X25518Y1314908I-2011J1D01*
G01Y1318108D01*
G37*
G36*
G01Y1330707D02*
G02X29540I2011J0D01*
G01Y1327506D01*
G02X25518Y1327507I-2011J1D01*
G01Y1330707D01*
G37*
G36*
G01Y1343305D02*
G02X29540I2011J0D01*
G01Y1340104D01*
G02X25518Y1340105I-2011J1D01*
G01Y1343305D01*
G37*
G36*
G01Y1355904D02*
G02X29540I2011J0D01*
G01Y1352703D01*
G02X25518Y1352704I-2011J1D01*
G01Y1355904D01*
G37*
G36*
G01X17988Y1362001D02*
G02X22012I2012J0D01*
G01Y1358800D01*
G02X17988Y1358801I-2012J1D01*
G01Y1362001D01*
G37*
G36*
G01Y1349402D02*
G02X22012I2012J0D01*
G01Y1346201D01*
G02X17988Y1346202I-2012J1D01*
G01Y1349402D01*
G37*
G36*
G01Y1336804D02*
G02X22012I2012J0D01*
G01Y1333603D01*
G02X17988Y1333604I-2012J1D01*
G01Y1336804D01*
G37*
G36*
G01Y1324206D02*
G02X22012I2012J0D01*
G01Y1321005D01*
G02X17988Y1321006I-2012J1D01*
G01Y1324206D01*
G37*
G36*
G01Y1302158D02*
G02X22012I2012J0D01*
G01Y1298957D01*
G02X17988Y1298958I-2012J1D01*
G01Y1302158D01*
G37*
G36*
G01Y1289560D02*
G02X22012I2012J0D01*
G01Y1286359D01*
G02X17988Y1286360I-2012J1D01*
G01Y1289560D01*
G37*
G36*
G01X29540Y1280063D02*
G02X25518I-2011J0D01*
G01Y1283264D01*
G02X29540Y1283263I2011J-1D01*
G01Y1280063D01*
G37*
G36*
G01Y1267464D02*
G02X25518I-2011J0D01*
G01Y1270665D01*
G02X29540Y1270664I2011J-1D01*
G01Y1267464D01*
G37*
G36*
G01Y1254866D02*
G02X25518I-2011J0D01*
G01Y1258067D01*
G02X29540Y1258066I2011J-1D01*
G01Y1254866D01*
G37*
G36*
G01Y1223370D02*
G02X25518I-2011J0D01*
G01Y1226571D01*
G02X29540Y1226570I2011J-1D01*
G01Y1223370D01*
G37*
G36*
G01X17988Y1276961D02*
G02X22012I2012J0D01*
G01Y1273760D01*
G02X17988Y1273761I-2012J1D01*
G01Y1276961D01*
G37*
G36*
G01Y1264363D02*
G02X22012I2012J0D01*
G01Y1261162D01*
G02X17988Y1261163I-2012J1D01*
G01Y1264363D01*
G37*
G36*
G01Y1220269D02*
G02X22012I2012J0D01*
G01Y1217068D01*
G02X17988Y1217069I-2012J1D01*
G01Y1220269D01*
G37*
G36*
G01X29540Y1210771D02*
G02X25518I-2011J0D01*
G01Y1213972D01*
G02X29540Y1213971I2011J-1D01*
G01Y1210771D01*
G37*
G36*
G01Y1198173D02*
G02X25518I-2011J0D01*
G01Y1201374D01*
G02X29540Y1201373I2011J-1D01*
G01Y1198173D01*
G37*
G36*
G01Y1185574D02*
G02X25518I-2011J0D01*
G01Y1188775D01*
G02X29540Y1188774I2011J-1D01*
G01Y1185574D01*
G37*
G36*
G01Y1172976D02*
G02X25518I-2011J0D01*
G01Y1176177D01*
G02X29540Y1176176I2011J-1D01*
G01Y1172976D01*
G37*
G36*
G01Y1160378D02*
G02X25518I-2011J0D01*
G01Y1163579D01*
G02X29540Y1163578I2011J-1D01*
G01Y1160378D01*
G37*
G36*
G01Y1147779D02*
G02X25518I-2011J0D01*
G01Y1150980D01*
G02X29540Y1150979I2011J-1D01*
G01Y1147779D01*
G37*
G36*
G01X17988Y1195072D02*
G02X22012I2012J0D01*
G01Y1191871D01*
G02X17988Y1191872I-2012J1D01*
G01Y1195072D01*
G37*
G36*
G01Y1207670D02*
G02X22012I2012J0D01*
G01Y1204469D01*
G02X17988Y1204470I-2012J1D01*
G01Y1207670D01*
G37*
G36*
G01Y1182473D02*
G02X22012I2012J0D01*
G01Y1179272D01*
G02X17988Y1179273I-2012J1D01*
G01Y1182473D01*
G37*
G36*
G01Y1169875D02*
G02X22012I2012J0D01*
G01Y1166674D01*
G02X17988Y1166675I-2012J1D01*
G01Y1169875D01*
G37*
G36*
G01Y1157276D02*
G02X22012I2012J0D01*
G01Y1154075D01*
G02X17988Y1154076I-2012J1D01*
G01Y1157276D01*
G37*
G36*
G01Y1144678D02*
G02X22012I2012J0D01*
G01Y1141477D01*
G02X17988Y1141478I-2012J1D01*
G01Y1144678D01*
G37*
G36*
G01X25518Y1113384D02*
G02X29540I2011J0D01*
G01Y1110183D01*
G02X25518Y1110184I-2011J1D01*
G01Y1113384D01*
G37*
G36*
G01Y1138381D02*
G02X29540I2011J0D01*
G01Y1135180D01*
G02X25518Y1135181I-2011J1D01*
G01Y1138381D01*
G37*
G36*
G01Y1100785D02*
G02X29540I2011J0D01*
G01Y1097584D01*
G02X25518Y1097585I-2011J1D01*
G01Y1100785D01*
G37*
G36*
G01X17988Y1119481D02*
G02X22012I2012J0D01*
G01Y1116280D01*
G02X17988Y1116281I-2012J1D01*
G01Y1119481D01*
G37*
G36*
G01Y1106883D02*
G02X22012I2012J0D01*
G01Y1103682D01*
G02X17988Y1103683I-2012J1D01*
G01Y1106883D01*
G37*
G36*
G01X25518Y859441D02*
G02X29540I2011J0D01*
G01Y856240D01*
G02X25518Y856241I-2011J1D01*
G01Y859441D01*
G37*
G36*
G01X29540Y868839D02*
G02X25518I-2011J0D01*
G01Y872040D01*
G02X29540Y872039I2011J-1D01*
G01Y868839D01*
G37*
G36*
G01X25518Y884687D02*
G02X29540I2011J0D01*
G01Y881486D01*
G02X25518Y881487I-2011J1D01*
G01Y884687D01*
G37*
G36*
G01Y910034D02*
G02X29540I2011J0D01*
G01Y906833D01*
G02X25518Y906834I-2011J1D01*
G01Y910034D01*
G37*
G36*
G01Y897436D02*
G02X29540I2011J0D01*
G01Y894235D01*
G02X25518Y894236I-2011J1D01*
G01Y897436D01*
G37*
G36*
G01X17988Y853339D02*
G02X22012I2012J0D01*
G01Y850138D01*
G02X17988Y850139I-2012J1D01*
G01Y853339D01*
G37*
G36*
G01Y865938D02*
G02X22012I2012J0D01*
G01Y862737D01*
G02X17988Y862738I-2012J1D01*
G01Y865938D01*
G37*
G36*
G01Y878536D02*
G02X22012I2012J0D01*
G01Y875335D01*
G02X17988Y875336I-2012J1D01*
G01Y878536D01*
G37*
G36*
G01Y903733D02*
G02X22012I2012J0D01*
G01Y900532D01*
G02X17988Y900533I-2012J1D01*
G01Y903733D01*
G37*
G36*
G01Y916332D02*
G02X22012I2012J0D01*
G01Y913131D01*
G02X17988Y913132I-2012J1D01*
G01Y916332D01*
G37*
G36*
G01X25518Y846842D02*
G02X29540I2011J0D01*
G01Y843641D01*
G02X25518Y843642I-2011J1D01*
G01Y846842D01*
G37*
G36*
G01Y834444D02*
G02X29540I2011J0D01*
G01Y831243D01*
G02X25518Y831244I-2011J1D01*
G01Y834444D01*
G37*
G36*
G01Y821845D02*
G02X29540I2011J0D01*
G01Y818644D01*
G02X25518Y818645I-2011J1D01*
G01Y821845D01*
G37*
G36*
G01Y809247D02*
G02X29540I2011J0D01*
G01Y806046D01*
G02X25518Y806047I-2011J1D01*
G01Y809247D01*
G37*
G36*
G01Y796648D02*
G02X29540I2011J0D01*
G01Y793447D01*
G02X25518Y793448I-2011J1D01*
G01Y796648D01*
G37*
G36*
G01X17988Y790347D02*
G02X22012I2012J0D01*
G01Y787146D01*
G02X17988Y787147I-2012J1D01*
G01Y790347D01*
G37*
G36*
G01Y802946D02*
G02X22012I2012J0D01*
G01Y799745D01*
G02X17988Y799746I-2012J1D01*
G01Y802946D01*
G37*
G36*
G01Y815544D02*
G02X22012I2012J0D01*
G01Y812343D01*
G02X17988Y812344I-2012J1D01*
G01Y815544D01*
G37*
G36*
G01Y828143D02*
G02X22012I2012J0D01*
G01Y824942D01*
G02X17988Y824943I-2012J1D01*
G01Y828143D01*
G37*
G36*
G01Y840741D02*
G02X22012I2012J0D01*
G01Y837540D01*
G02X17988Y837541I-2012J1D01*
G01Y840741D01*
G37*
G36*
G01X25518Y774601D02*
G02X29540I2011J0D01*
G01Y771400D01*
G02X25518Y771401I-2011J1D01*
G01Y774601D01*
G37*
G36*
G01Y762003D02*
G02X29540I2011J0D01*
G01Y758802D01*
G02X25518Y758803I-2011J1D01*
G01Y762003D01*
G37*
G36*
G01Y730507D02*
G02X29540I2011J0D01*
G01Y727306D01*
G02X25518Y727307I-2011J1D01*
G01Y730507D01*
G37*
G36*
G01Y717908D02*
G02X29540I2011J0D01*
G01Y714707D01*
G02X25518Y714708I-2011J1D01*
G01Y717908D01*
G37*
G36*
G01X17988Y768300D02*
G02X22012I2012J0D01*
G01Y765099D01*
G02X17988Y765100I-2012J1D01*
G01Y768300D01*
G37*
G36*
G01Y724206D02*
G02X22012I2012J0D01*
G01Y721005D01*
G02X17988Y721006I-2012J1D01*
G01Y724206D01*
G37*
G36*
G01Y711607D02*
G02X22012I2012J0D01*
G01Y708406D01*
G02X17988Y708407I-2012J1D01*
G01Y711607D01*
G37*
G36*
G01Y636017D02*
G02X22012I2012J0D01*
G01Y632816D01*
G02X17988Y632817I-2012J1D01*
G01Y636017D01*
G37*
G36*
G01Y699009D02*
G02X22012I2012J0D01*
G01Y695808D01*
G02X17988Y695809I-2012J1D01*
G01Y699009D01*
G37*
G36*
G01X25518Y642518D02*
G02X29540I2011J0D01*
G01Y639317D01*
G02X25518Y639318I-2011J1D01*
G01Y642518D01*
G37*
G36*
G01Y667715D02*
G02X29540I2011J0D01*
G01Y664514D01*
G02X25518Y664515I-2011J1D01*
G01Y667715D01*
G37*
G36*
G01Y680313D02*
G02X29540I2011J0D01*
G01Y677112D01*
G02X25518Y677113I-2011J1D01*
G01Y680313D01*
G37*
G36*
G01Y692911D02*
G02X29540I2011J0D01*
G01Y689710D01*
G02X25518Y689711I-2011J1D01*
G01Y692911D01*
G37*
G36*
G01Y705510D02*
G02X29540I2011J0D01*
G01Y702309D01*
G02X25518Y702310I-2011J1D01*
G01Y705510D01*
G37*
G36*
G01X17988Y686410D02*
G02X22012I2012J0D01*
G01Y683209D01*
G02X17988Y683210I-2012J1D01*
G01Y686410D01*
G37*
G36*
G01Y673812D02*
G02X22012I2012J0D01*
G01Y670611D01*
G02X17988Y670612I-2012J1D01*
G01Y673812D01*
G37*
G36*
G01Y661213D02*
G02X22012I2012J0D01*
G01Y658012D01*
G02X17988Y658013I-2012J1D01*
G01Y661213D01*
G37*
G36*
G01Y648615D02*
G02X22012I2012J0D01*
G01Y645414D01*
G02X17988Y645415I-2012J1D01*
G01Y648615D01*
G37*
G36*
G01X25518Y617271D02*
G02X29540I2011J0D01*
G01Y614070D01*
G02X25518Y614071I-2011J1D01*
G01Y617271D01*
G37*
G36*
G01Y604722D02*
G02X29540I2011J0D01*
G01Y601521D01*
G02X25518Y601522I-2011J1D01*
G01Y604722D01*
G37*
G36*
G01Y629919D02*
G02X29540I2011J0D01*
G01Y626718D01*
G02X25518Y626719I-2011J1D01*
G01Y629919D01*
G37*
G36*
G01X17988Y623418D02*
G02X22012I2012J0D01*
G01Y620217D01*
G02X17988Y620218I-2012J1D01*
G01Y623418D01*
G37*
G36*
G01Y610820D02*
G02X22012I2012J0D01*
G01Y607619D01*
G02X17988Y607620I-2012J1D01*
G01Y610820D01*
G37*
G36*
G01X49214Y281496D02*
Y267716D01*
G02X17716I-15749J1D01*
G01Y281496D01*
G02X49214I15749J0D01*
G37*
G36*
G01X671750Y272689D02*
X668811Y269750D01*
X383189D01*
X286750Y366189D01*
Y584671D01*
G02Y588297I1250J1813D01*
G01Y656516D01*
X295306Y665072D01*
Y698133D01*
X286750Y706689D01*
Y1062028D01*
X295306Y1070584D01*
Y1096133D01*
X286750Y1104689D01*
Y1353811D01*
X502689Y1569750D01*
X668811D01*
X671750Y1566811D01*
Y272689D01*
G37*
G54D32*
X82087Y28858D03*
Y178464D03*
Y434370D03*
Y583976D03*
Y839882D03*
Y989488D03*
Y1245394D03*
Y1395000D03*
Y1650906D03*
Y1800512D03*
X162008Y191614D03*
Y341220D03*
Y597126D03*
Y746732D03*
Y1002638D03*
Y1152244D03*
Y1408150D03*
Y1557756D03*
Y1813662D03*
Y1963268D03*
X890354Y191614D03*
Y341220D03*
Y597126D03*
Y746732D03*
Y1002638D03*
Y1152244D03*
Y1408150D03*
Y1557756D03*
Y1813662D03*
Y1963268D03*
G54D31*
X25499Y1950499D03*
X1010999Y43999D03*
X1010499Y1950499D03*
G54D29*
X11811Y571426D03*
Y949378D03*
Y1067489D03*
Y1484811D03*
Y1445441D03*
Y1862763D03*
G54D27*
X998032Y1896644D03*
G54D30*
X33469Y1029523D03*
X269690Y1490152D03*
G54D28*
X998032Y1075778D03*
Y680108D03*
Y156486D03*
%LPC*%
G75*
G36*
G01X288250Y584290D02*
X288413Y584321D01*
G03Y588647I-413J2163D01*
G01X288250Y588678D01*
Y615104D01*
X288257Y615130D01*
G03Y616270I-2127J570D01*
G01X288250Y616296D01*
Y655894D01*
X296806Y664450D01*
Y698755D01*
X288250Y707311D01*
Y1061406D01*
X296806Y1069962D01*
Y1096755D01*
X288250Y1105311D01*
Y1353189D01*
X503311Y1568250D01*
X668189D01*
X670250Y1566189D01*
Y273311D01*
X668189Y271250D01*
X383811D01*
X288250Y366811D01*
Y584290D01*
G37*
%LPD*%
G75*
G54D19*
X72835Y17047D03*
Y190275D03*
Y422559D03*
Y595787D03*
Y828071D03*
Y1001299D03*
Y1233583D03*
Y1406811D03*
Y1639095D03*
Y1812323D03*
X171260Y179803D03*
Y353031D03*
Y585315D03*
Y758543D03*
Y990827D03*
Y1164055D03*
Y1396339D03*
Y1569567D03*
Y1801851D03*
Y1975079D03*
X899606Y179803D03*
Y353031D03*
Y585315D03*
Y758543D03*
Y990827D03*
Y1164055D03*
Y1396339D03*
Y1569567D03*
Y1801851D03*
Y1975079D03*
G54D11*
X20000Y40000D03*
Y20000D03*
X5500Y40982D03*
Y20982D03*
X10018Y5500D03*
X30018D03*
X20000Y80000D03*
Y100000D03*
Y120000D03*
Y60000D03*
X5500Y120982D03*
Y100982D03*
Y80982D03*
Y60982D03*
X20000Y160000D03*
Y180000D03*
Y140000D03*
X5500Y180982D03*
Y160982D03*
Y140982D03*
X20000Y240000D03*
Y200000D03*
Y220000D03*
X5500Y260982D03*
Y240982D03*
Y220982D03*
Y200982D03*
Y320982D03*
Y300982D03*
Y280982D03*
X27500Y380000D03*
X20000D03*
Y400000D03*
X5500Y400982D03*
Y380982D03*
Y360982D03*
Y340982D03*
X20000Y340000D03*
X27000Y440000D03*
X20000Y460000D03*
Y440000D03*
Y480000D03*
Y420000D03*
X5500Y480982D03*
Y460982D03*
Y440982D03*
Y420982D03*
X27500Y540000D03*
Y553500D03*
X20000Y540000D03*
Y500000D03*
Y520000D03*
X5500Y540982D03*
Y520982D03*
Y500982D03*
X24500Y624897D03*
Y612249D03*
Y619093D03*
Y606544D03*
Y599700D03*
X16500Y624765D03*
Y618765D03*
Y612166D03*
Y606166D03*
Y598197D03*
X20000Y607620D03*
Y610820D03*
Y620218D03*
Y623418D03*
X27529Y601522D03*
Y604722D03*
Y614071D03*
Y617271D03*
Y626719D03*
Y629919D03*
X24500Y700488D03*
Y694733D03*
Y687889D03*
Y675291D03*
Y682135D03*
Y669537D03*
Y662693D03*
Y637496D03*
Y644340D03*
Y631741D03*
X16500Y700355D03*
Y694355D03*
Y687757D03*
Y681757D03*
Y675158D03*
Y669158D03*
Y662226D03*
Y657000D03*
Y649500D03*
Y644530D03*
Y637363D03*
Y631363D03*
X20000Y658013D03*
Y661213D03*
Y670612D03*
Y673812D03*
Y683210D03*
Y686410D03*
Y632817D03*
Y636017D03*
Y695809D03*
Y699009D03*
Y645415D03*
Y648615D03*
X27529Y664515D03*
Y667715D03*
Y677113D03*
Y680313D03*
Y689711D03*
Y692911D03*
Y702310D03*
Y639318D03*
Y642518D03*
X24500Y769579D03*
Y763825D03*
Y756981D03*
Y725485D03*
Y732329D03*
Y719730D03*
Y712886D03*
Y707332D03*
X16500Y769646D03*
Y763646D03*
Y757048D03*
Y725552D03*
Y719552D03*
Y712953D03*
Y706953D03*
Y751658D03*
Y732500D03*
X20000Y708407D03*
Y711607D03*
Y721006D03*
Y724206D03*
Y752502D03*
Y755702D03*
Y765100D03*
Y768300D03*
X27529Y714708D03*
Y717908D03*
Y727307D03*
Y730507D03*
Y758803D03*
Y762003D03*
Y705510D03*
Y771401D03*
Y774601D03*
X27699Y737535D03*
X24500Y848664D03*
Y841820D03*
Y836266D03*
Y829422D03*
Y816823D03*
Y823667D03*
Y804225D03*
Y811069D03*
Y798470D03*
Y791626D03*
Y776423D03*
X16500Y848686D03*
Y842087D03*
Y836087D03*
Y829489D03*
Y823489D03*
Y816891D03*
Y810891D03*
Y804292D03*
Y798292D03*
Y791694D03*
Y785694D03*
Y777725D03*
X20000Y837541D03*
Y840741D03*
Y787147D03*
Y790347D03*
Y799746D03*
Y802946D03*
Y812344D03*
Y815544D03*
Y824943D03*
Y828143D03*
X27529Y843642D03*
Y846842D03*
Y793448D03*
Y796648D03*
Y806047D03*
Y809247D03*
Y818645D03*
Y821845D03*
Y831244D03*
Y834444D03*
X24500Y911856D03*
Y905012D03*
Y892414D03*
Y899258D03*
Y886509D03*
Y879665D03*
Y867017D03*
Y873861D03*
Y854419D03*
Y861263D03*
X16500Y917678D03*
Y911678D03*
Y905079D03*
Y899079D03*
Y879883D03*
Y873883D03*
Y867284D03*
Y861284D03*
Y854686D03*
Y889500D03*
X20000Y900533D03*
Y903733D03*
Y850139D03*
Y853339D03*
Y913132D03*
Y916332D03*
Y862738D03*
Y865938D03*
Y875336D03*
Y878536D03*
X27529Y894236D03*
Y897436D03*
Y856241D03*
Y859441D03*
Y906834D03*
Y910034D03*
Y868839D03*
Y872039D03*
Y881487D03*
Y884687D03*
X34872Y890906D03*
X36000Y960000D03*
X20000Y980000D03*
Y960000D03*
Y940000D03*
X16000Y931000D03*
X34500Y925000D03*
X5500Y980299D03*
X30000Y991000D03*
X36500Y999500D03*
X5500Y1040299D03*
Y1020299D03*
Y1000299D03*
X23291Y1062791D03*
X24500Y1133365D03*
Y1102601D03*
Y1095769D03*
Y1108368D03*
Y1115200D03*
X16500Y1140024D03*
Y1120828D03*
Y1114828D03*
Y1108229D03*
Y1102229D03*
Y1133500D03*
Y1094260D03*
X31707Y1086000D03*
X20000Y1103683D03*
Y1106883D03*
Y1116281D03*
Y1119481D03*
X27529Y1135181D03*
Y1138381D03*
Y1097585D03*
Y1100785D03*
Y1110184D03*
Y1113384D03*
X32335Y1122002D03*
X37396Y1130912D03*
X33971Y1131741D03*
X24500Y1208955D03*
Y1196357D03*
Y1203189D03*
Y1183758D03*
Y1190590D03*
Y1171160D03*
Y1177992D03*
Y1165394D03*
Y1158562D03*
Y1152795D03*
Y1145963D03*
Y1140197D03*
X16500Y1209016D03*
Y1203016D03*
Y1196418D03*
Y1190418D03*
Y1183820D03*
Y1177820D03*
Y1171221D03*
Y1165221D03*
Y1158623D03*
Y1152623D03*
Y1146024D03*
X20000Y1141478D03*
Y1144678D03*
Y1191872D03*
Y1195072D03*
Y1154076D03*
Y1157276D03*
Y1204470D03*
Y1207670D03*
Y1166675D03*
Y1169875D03*
Y1179273D03*
Y1182473D03*
X27529Y1185574D03*
Y1188774D03*
Y1147779D03*
Y1150979D03*
Y1198173D03*
Y1201373D03*
Y1160378D03*
Y1163578D03*
Y1210771D03*
Y1172976D03*
Y1176176D03*
X24500Y1285079D03*
Y1278247D03*
Y1272480D03*
Y1265648D03*
Y1259882D03*
Y1253050D03*
Y1228386D03*
Y1221554D03*
Y1215787D03*
X16500Y1284906D03*
Y1278308D03*
Y1272308D03*
Y1265709D03*
Y1259709D03*
Y1253111D03*
Y1247721D03*
Y1221615D03*
Y1215615D03*
Y1228500D03*
X20000Y1261163D03*
Y1264363D03*
Y1273761D03*
Y1276961D03*
Y1217069D03*
Y1220269D03*
Y1248565D03*
Y1251765D03*
X27529Y1254866D03*
Y1258066D03*
Y1267464D03*
Y1270664D03*
Y1280063D03*
Y1283263D03*
Y1213971D03*
Y1223370D03*
Y1226570D03*
X33201Y1230674D03*
X32959Y1234478D03*
X36000Y1236000D03*
X24500Y1357720D03*
Y1350888D03*
Y1345121D03*
Y1338289D03*
Y1332523D03*
Y1325691D03*
Y1319924D03*
Y1313092D03*
Y1290845D03*
Y1297677D03*
X34000Y1321000D03*
X16500Y1357347D03*
Y1350749D03*
Y1344749D03*
Y1338150D03*
Y1332150D03*
Y1325552D03*
Y1319552D03*
Y1303505D03*
Y1297505D03*
Y1290906D03*
X16417Y1311583D03*
X20000Y1321006D03*
Y1324206D03*
Y1333604D03*
Y1336804D03*
Y1346202D03*
Y1349402D03*
Y1286360D03*
Y1289560D03*
Y1298958D03*
Y1302158D03*
X27529Y1314908D03*
Y1318108D03*
Y1327507D03*
Y1330707D03*
Y1340105D03*
Y1343305D03*
Y1352704D03*
Y1355904D03*
Y1292661D03*
Y1295861D03*
X36170Y1308434D03*
X33699Y1301782D03*
X26500Y1305121D03*
X33938Y1311000D03*
X38500D03*
X30000Y1305000D03*
X30700Y1308600D03*
X24500Y1401081D03*
Y1407913D03*
Y1388483D03*
Y1395315D03*
Y1375884D03*
Y1382716D03*
Y1370118D03*
Y1363286D03*
X21000Y1424500D03*
X16500Y1413741D03*
Y1407741D03*
Y1401142D03*
Y1395142D03*
Y1388544D03*
Y1382544D03*
Y1375946D03*
Y1369946D03*
Y1363347D03*
X20000Y1371399D03*
Y1374599D03*
Y1383998D03*
Y1387198D03*
Y1396596D03*
Y1399796D03*
Y1358801D03*
Y1362001D03*
Y1409195D03*
Y1412395D03*
X27529Y1365102D03*
Y1368302D03*
Y1377700D03*
Y1380900D03*
Y1390299D03*
Y1393499D03*
Y1402897D03*
Y1406097D03*
X27000Y1417500D03*
X32500Y1417600D03*
X22000Y1487000D03*
X37000Y1443500D03*
X30500Y1463500D03*
X28000Y1444000D03*
X36401Y1521623D03*
X32801D03*
X24500Y1560197D03*
Y1566907D03*
Y1547598D03*
Y1554308D03*
Y1522401D03*
Y1529111D03*
Y1541710D03*
Y1535000D03*
X16500Y1573000D03*
Y1566500D03*
Y1560500D03*
Y1554000D03*
Y1548000D03*
Y1541500D03*
Y1535000D03*
Y1529000D03*
Y1521031D03*
Y1512500D03*
X20000Y1530454D03*
Y1533654D03*
Y1543052D03*
Y1546252D03*
Y1555650D03*
Y1558850D03*
Y1568249D03*
Y1571449D03*
X27529Y1524156D03*
Y1527356D03*
Y1536755D03*
Y1539955D03*
Y1549353D03*
Y1552553D03*
Y1561952D03*
Y1565152D03*
X33001Y1518123D03*
X36201D03*
X24500Y1632638D03*
Y1639348D03*
Y1626749D03*
Y1620039D03*
Y1614151D03*
Y1607441D03*
Y1601552D03*
Y1594842D03*
Y1588954D03*
Y1582244D03*
X16500Y1644735D03*
Y1639845D03*
Y1633000D03*
Y1626500D03*
Y1620000D03*
Y1614000D03*
Y1607500D03*
Y1601500D03*
Y1595000D03*
Y1588500D03*
Y1582500D03*
X20000Y1640690D03*
Y1643890D03*
Y1593496D03*
Y1590296D03*
Y1606094D03*
Y1602894D03*
Y1618693D03*
Y1615493D03*
Y1631291D03*
Y1628091D03*
X27529Y1634393D03*
Y1637593D03*
Y1587199D03*
Y1583999D03*
Y1599797D03*
Y1596597D03*
Y1612396D03*
Y1609196D03*
Y1624994D03*
Y1621794D03*
X24500Y1717868D03*
Y1702531D03*
Y1695821D03*
Y1689932D03*
Y1683222D03*
Y1677334D03*
Y1670624D03*
X16500Y1669933D03*
Y1677000D03*
Y1683170D03*
Y1689500D03*
Y1696000D03*
Y1702500D03*
Y1712000D03*
Y1717462D03*
Y1665044D03*
X20000Y1716331D03*
Y1713131D03*
Y1665887D03*
Y1669087D03*
Y1678485D03*
Y1681685D03*
Y1691083D03*
Y1694283D03*
X27529Y1719623D03*
Y1672379D03*
Y1675579D03*
Y1684977D03*
Y1688177D03*
Y1697576D03*
Y1700776D03*
X35900Y1706000D03*
X34224Y1709000D03*
X38000Y1715000D03*
X31981Y1768323D03*
X24500Y1755663D03*
Y1762373D03*
Y1743065D03*
Y1749775D03*
Y1730466D03*
Y1737176D03*
Y1724578D03*
X22219Y1768323D03*
X16500Y1749000D03*
Y1756052D03*
Y1765000D03*
Y1774500D03*
Y1784000D03*
Y1790500D03*
Y1724000D03*
Y1730658D03*
Y1736500D03*
Y1743356D03*
X20000Y1728929D03*
Y1725729D03*
Y1741528D03*
Y1738328D03*
Y1754126D03*
Y1750926D03*
X27529Y1722823D03*
Y1735421D03*
Y1732221D03*
Y1748020D03*
Y1744820D03*
Y1760618D03*
Y1757418D03*
X25500Y1769558D03*
X28700D03*
X39500Y1823300D03*
X39400Y1819900D03*
X38400Y1846750D03*
X38300Y1859050D03*
X5500Y1880685D03*
Y1888685D03*
X38500Y1871350D03*
X38200Y1883800D03*
X19974Y1943969D03*
X33700Y1960300D03*
X20000Y1960000D03*
Y1980000D03*
X32559Y1986626D03*
X12559D03*
X5500Y1973685D03*
Y1953685D03*
X30200Y1970300D03*
X40000Y40000D03*
Y20000D03*
X90018Y5500D03*
X110018D03*
X50018D03*
X70018D03*
X109038Y62310D03*
X109000Y81106D03*
X109160Y105900D03*
X60000Y80000D03*
X40000D03*
Y100000D03*
Y120000D03*
Y60000D03*
X109038Y68476D03*
X109000Y87476D03*
X109160Y100476D03*
X96000Y114212D03*
Y107913D03*
Y98464D03*
Y89015D03*
Y79567D03*
Y70118D03*
Y60868D03*
X96100Y52300D03*
X72500Y91161D03*
Y86161D03*
X71000Y58000D03*
X96000Y119000D03*
X99500Y95940D03*
Y91540D03*
Y77042D03*
Y72642D03*
Y58244D03*
Y53844D03*
X105000Y104788D03*
Y101588D03*
Y85891D03*
Y82691D03*
Y66993D03*
Y63793D03*
X72500Y61161D03*
X67500Y124088D03*
X108917Y150188D03*
X100000Y180000D03*
X99800Y194200D03*
X40000Y160000D03*
Y180000D03*
Y140000D03*
X67500Y135830D03*
X108917Y156976D03*
X72500Y166161D03*
X96000Y158307D03*
X72500Y151161D03*
X96000Y148858D03*
X72500Y136161D03*
X96000Y139409D03*
Y134000D03*
Y123661D03*
X104000Y125000D03*
X71000Y125236D03*
X68000Y128359D03*
Y131559D03*
X99500Y146333D03*
Y141933D03*
X105000Y155182D03*
Y151982D03*
X85250Y247238D03*
X80000Y200000D03*
X77306Y259381D03*
X40000Y240000D03*
Y200000D03*
Y220000D03*
X60306Y212338D03*
X80153Y230246D03*
X85427Y239715D03*
X100400Y208300D03*
X70500Y242988D03*
X80300Y234465D03*
X97400Y220200D03*
X97000Y296500D03*
X111500Y276000D03*
X84500Y315000D03*
X67000Y269000D03*
X66512Y287899D03*
X66610Y295956D03*
X56024Y292549D03*
X97400Y366600D03*
X95849Y361564D03*
X46487Y360400D03*
X48822Y393916D03*
X100400Y406000D03*
X104400D03*
X107900D03*
X96900D03*
X92700Y358400D03*
X52066Y370649D03*
X109044Y467822D03*
X51500Y469000D03*
X112600Y442500D03*
X98300Y443400D03*
X109044Y473988D03*
X96000Y485079D03*
Y475630D03*
Y466181D03*
Y456732D03*
X71000Y463500D03*
X112600Y439000D03*
X99500Y482554D03*
Y478154D03*
Y463656D03*
Y459256D03*
X105000Y472505D03*
Y469305D03*
X72500Y466673D03*
X109000Y486618D03*
X109138Y505912D03*
X67500Y529600D03*
X108917Y555700D03*
X67500Y541342D03*
X109000Y492988D03*
X109138Y511488D03*
X72500Y556673D03*
X96000Y554369D03*
X72500Y541673D03*
X96000Y544921D03*
Y539500D03*
Y529173D03*
Y519724D03*
Y513425D03*
Y503976D03*
Y494527D03*
X72500Y496673D03*
Y491673D03*
X104000Y531000D03*
X71000Y530748D03*
X96000Y524000D03*
X68000Y533871D03*
Y537071D03*
X99500Y551845D03*
Y547445D03*
Y501452D03*
Y497052D03*
X105000Y557494D03*
Y510300D03*
Y507100D03*
Y491403D03*
Y488203D03*
X71000Y524464D03*
X99900Y582400D03*
X61100Y600100D03*
X61900Y584300D03*
X72900Y605400D03*
X94700Y599800D03*
X80000Y600000D03*
X108917Y562488D03*
X72500Y571673D03*
X96000Y563819D03*
X95900Y605500D03*
X62426Y607740D03*
X105000Y560694D03*
X88600Y623300D03*
X85250Y652750D03*
X61500Y682500D03*
X59000Y659500D03*
X49000Y638000D03*
X76500Y665000D03*
X80153Y635758D03*
X85223Y645227D03*
X70500Y648500D03*
X48000Y649500D03*
X46500Y653500D03*
X80300Y639977D03*
X50560Y653500D03*
X97000Y772100D03*
X87075Y768250D03*
X102500Y737500D03*
X83200Y768300D03*
X76000Y706500D03*
X62000Y736500D03*
X61500Y748000D03*
X51500Y730500D03*
Y757500D03*
X86900Y774750D03*
X49500Y771000D03*
X67500Y822500D03*
X63100Y788800D03*
X73500Y779500D03*
X100600Y811300D03*
X104600D03*
X108100D03*
X97100D03*
X112500Y848700D03*
Y845200D03*
X80215Y777137D03*
X109040Y873334D03*
X109000Y892130D03*
X109187Y911424D03*
X51000Y913500D03*
X63500Y899000D03*
X65500Y867500D03*
X98300Y850400D03*
X109040Y879500D03*
X109000Y898500D03*
X109187Y917000D03*
X96000Y918937D03*
Y909488D03*
Y900039D03*
Y890591D03*
Y881142D03*
Y871692D03*
Y862244D03*
X72500Y902185D03*
Y897185D03*
X71000Y869000D03*
X47500Y901500D03*
X99500Y906964D03*
Y902564D03*
Y888066D03*
Y883666D03*
Y869168D03*
Y864768D03*
X105000Y915812D03*
Y912612D03*
Y896915D03*
Y893715D03*
Y878017D03*
Y874817D03*
X72500Y872185D03*
X67500Y935111D03*
X109000Y961212D03*
X67000Y953500D03*
X96532Y977682D03*
X107400Y994000D03*
X67500Y946855D03*
X109000Y968000D03*
X72500Y977185D03*
X96000Y969331D03*
X72500Y962185D03*
X96000Y959882D03*
X72500Y947185D03*
X96000Y950433D03*
Y945000D03*
Y934685D03*
Y925236D03*
X104000Y936000D03*
X96000Y930000D03*
X71000Y936260D03*
X68000Y939383D03*
Y942583D03*
X99500Y957357D03*
Y952957D03*
X105000Y966206D03*
Y963006D03*
X65500Y927500D03*
X71000Y925500D03*
X99600Y1001400D03*
X102403Y1058209D03*
X103200Y1042500D03*
X83248Y1059636D03*
X81689Y1039600D03*
X77750Y1056750D03*
X96500Y1011200D03*
X64037Y1016654D03*
X74000Y1047500D03*
X41000Y1057500D03*
X81689Y1049400D03*
X106100Y1030000D03*
X71000Y1109000D03*
X42286Y1089500D03*
Y1085500D03*
X67090Y1070360D03*
X41608Y1125065D03*
X39959Y1128308D03*
X96100Y1176700D03*
X87900Y1173300D03*
X111500Y1145000D03*
X75000Y1182500D03*
X41500Y1165500D03*
Y1178000D03*
X67500Y1191500D03*
X88500Y1177300D03*
X40097Y1142513D03*
X85300Y1182000D03*
X109040Y1278846D03*
X81500Y1213000D03*
X99100Y1219800D03*
X104500Y1217000D03*
X108000D03*
X95700Y1219700D03*
X112600Y1254300D03*
X98300Y1255900D03*
X109040Y1285012D03*
X96000Y1277205D03*
Y1267756D03*
X71000Y1274500D03*
X112600Y1250800D03*
X99500Y1274680D03*
Y1270280D03*
X105000Y1283529D03*
Y1280329D03*
X72500Y1277697D03*
X109000Y1297642D03*
X109133Y1316936D03*
X67500Y1340624D03*
X64000Y1328500D03*
X58500Y1320500D03*
X67500Y1352366D03*
X109000Y1304012D03*
X109133Y1322512D03*
X72500Y1352697D03*
X96000Y1355945D03*
Y1350500D03*
Y1340197D03*
Y1330748D03*
Y1324449D03*
Y1315000D03*
Y1305551D03*
Y1296103D03*
Y1286654D03*
X72500Y1307697D03*
Y1302697D03*
X104000Y1341000D03*
X71000Y1341772D03*
X96000Y1335000D03*
X68000Y1344895D03*
Y1348095D03*
X99500Y1312476D03*
Y1308076D03*
Y1293578D03*
Y1289178D03*
X105000Y1321324D03*
Y1318124D03*
Y1302427D03*
Y1299227D03*
X71000Y1335488D03*
X58900Y1317000D03*
X109000Y1366724D03*
Y1373512D03*
X70838Y1384165D03*
X96000Y1374843D03*
X72285Y1365633D03*
X96000Y1365393D03*
X62962Y1422600D03*
X100000Y1423000D03*
X99900Y1419600D03*
X99500Y1362869D03*
Y1358469D03*
X105000Y1371718D03*
Y1368518D03*
X48000Y1482000D03*
X82748Y1465560D03*
X80000Y1480000D03*
X109500Y1486000D03*
X110000Y1470000D03*
X99300Y1431200D03*
X82748Y1455148D03*
X76750Y1462762D03*
X80153Y1446781D03*
X73000Y1455100D03*
X69365Y1474719D03*
X80300Y1451000D03*
X88076Y1575924D03*
X90500Y1521500D03*
X96000Y1541100D03*
X72000Y1551500D03*
X72100Y1536400D03*
Y1509900D03*
X48000Y1505500D03*
X91125Y1565900D03*
X105700Y1548200D03*
X82005Y1540500D03*
X85808D03*
X80465Y1570120D03*
X109050Y1540600D03*
X46893Y1519979D03*
X47368Y1527323D03*
X42644Y1521957D03*
X46845Y1514264D03*
X43000Y1526000D03*
X42960Y1517408D03*
X64500Y1581500D03*
X100500Y1622500D03*
X104500D03*
X108000D03*
X97000D03*
X40500Y1608500D03*
X42919Y1583175D03*
X64525Y1591016D03*
X109040Y1684358D03*
X109000Y1703154D03*
X66500Y1694000D03*
X68000Y1651500D03*
X98600Y1659800D03*
X109040Y1690524D03*
X109000Y1709524D03*
X96000Y1701615D03*
Y1711063D03*
Y1673268D03*
X72500Y1708209D03*
X96000Y1682716D03*
Y1692166D03*
X71000Y1680000D03*
X72500Y1713209D03*
X96000Y1720512D03*
X99500Y1713588D03*
Y1717988D03*
Y1694690D03*
Y1699090D03*
Y1675792D03*
Y1680192D03*
X105000Y1704739D03*
Y1707939D03*
Y1685841D03*
Y1689041D03*
X72500Y1683209D03*
X51635Y1665355D03*
X66400Y1706900D03*
X109137Y1722448D03*
X67500Y1757886D03*
X109030Y1778736D03*
X100000Y1780000D03*
X67500Y1746128D03*
X109137Y1728024D03*
X109030Y1772524D03*
X96000Y1729961D03*
Y1736260D03*
Y1745109D03*
Y1755158D03*
Y1761457D03*
Y1770906D03*
X72500Y1758209D03*
Y1773209D03*
Y1788209D03*
X96000Y1780355D03*
X100000Y1759000D03*
X71000Y1747284D03*
X104000Y1747800D03*
X68000Y1750407D03*
Y1753607D03*
X99500Y1763981D03*
Y1768381D03*
X105000Y1774030D03*
Y1777230D03*
Y1723636D03*
Y1726836D03*
X67000Y1738000D03*
X71015D03*
X93600Y1848200D03*
X45100Y1850800D03*
X42300Y1846750D03*
X42200Y1859050D03*
X45200Y1839300D03*
Y1843300D03*
Y1854700D03*
X40800Y1832300D03*
Y1827300D03*
X76975Y1864000D03*
X77159Y1818277D03*
X91036Y1835282D03*
X72123Y1841183D03*
X100287Y1825915D03*
X100300Y1830000D03*
X80600Y1848900D03*
X98000Y1848800D03*
X85000Y1817100D03*
X74100Y1796200D03*
X67800Y1855200D03*
X93625Y1802200D03*
X52000Y1877500D03*
X100000Y1928000D03*
X80000D03*
X60000D03*
X74300Y1900000D03*
X107543Y1898024D03*
X111000Y1879570D03*
X100100Y1896300D03*
X80000Y1920000D03*
X60000D03*
Y1900000D03*
X44000D03*
X40556Y1917072D03*
X40000Y1940000D03*
X52000Y1887500D03*
X41700Y1883700D03*
X42100Y1871350D03*
X112366Y1883985D03*
X46868Y1887765D03*
X60897Y1885848D03*
X48000Y1877500D03*
X110700Y1974100D03*
X80000Y1980000D03*
X100300Y1980900D03*
X71666Y1961325D03*
X43935Y1957215D03*
X56875Y1954250D03*
X40000Y1980000D03*
X112559Y1986626D03*
X92559D03*
X72559D03*
X52559D03*
X94700Y1974100D03*
X98800D03*
X103300D03*
X107000D03*
X170034Y31475D03*
X155018Y5500D03*
X170018D03*
X116600Y46800D03*
X152400Y41500D03*
X180000Y80000D03*
X160000D03*
X140000D03*
X154700Y65000D03*
X150200D03*
X141700Y64900D03*
X138200D03*
X131700Y61300D03*
X128200D03*
X121600Y54700D03*
X184461Y103368D03*
X125700Y54400D03*
X179147Y137913D03*
X180000Y180000D03*
X124000Y135859D03*
Y124059D03*
X147125Y160500D03*
X158300Y135200D03*
X150557Y142854D03*
X167298Y147703D03*
X159500Y181000D03*
X124000Y128359D03*
Y131559D03*
X167298Y151203D03*
X114579Y137775D03*
X154875Y160500D03*
X135064Y213390D03*
X134941Y264178D03*
X135500Y200500D03*
X125500Y265500D03*
X132500Y236000D03*
X128500Y248000D03*
X176492Y231103D03*
X180100Y231095D03*
X135064Y219602D03*
X171595Y203917D03*
X148095Y211771D03*
X171595Y218917D03*
X148095Y221220D03*
X171595Y233917D03*
X148095Y230669D03*
Y236968D03*
Y246417D03*
Y255866D03*
Y262165D03*
X140000Y247500D03*
X173095Y244842D03*
X148000Y241500D03*
X180000Y235394D03*
X176800D03*
X144595Y223745D03*
Y228145D03*
X139095Y214896D03*
Y218096D03*
Y265290D03*
X172900Y249400D03*
X143600Y252100D03*
X129000Y255500D03*
X135095Y288972D03*
X134995Y301768D03*
X126000Y293000D03*
X125000Y312000D03*
X145800Y332400D03*
X131300D03*
X134941Y269602D03*
X135095Y282602D03*
X134995Y307602D03*
X148095Y271614D03*
Y281063D03*
Y290511D03*
Y299960D03*
Y309409D03*
Y318858D03*
X171595Y278917D03*
Y283917D03*
X173000Y312500D03*
X131300Y335900D03*
X126445Y338300D03*
X114295D03*
X144595Y274138D03*
Y278538D03*
Y293036D03*
Y297436D03*
Y311934D03*
Y316334D03*
X139095Y268490D03*
Y284187D03*
Y287387D03*
Y303085D03*
Y306285D03*
X171595Y308917D03*
X145900Y408500D03*
X119159Y405100D03*
X124466Y370025D03*
X143500Y370000D03*
X147000D03*
X139500D03*
X136000D03*
X173800Y379800D03*
X157200Y412000D03*
X158500Y408000D03*
X148700Y413400D03*
X180000Y480000D03*
X163500Y423000D03*
X180000Y460000D03*
X120000D03*
X140000Y480000D03*
Y460000D03*
X160000Y440000D03*
X140000D03*
X120800Y438000D03*
X170500Y478500D03*
X125300Y438000D03*
X157500Y551200D03*
X160000Y520000D03*
X180000D03*
X124000Y541373D03*
Y529573D03*
X165138Y536500D03*
X174000Y553500D03*
X157750Y541250D03*
X184500Y553500D03*
X124000Y533873D03*
Y537073D03*
X157750Y544750D03*
X135095Y625402D03*
X158500Y569500D03*
X131500Y610500D03*
X180000Y620000D03*
Y580000D03*
X139500Y600400D03*
X180000Y600000D03*
X135095Y618614D03*
X171595Y609429D03*
X148095Y617283D03*
X171595Y624429D03*
X148095Y626732D03*
X132350Y563750D03*
X159600Y581400D03*
X155500Y574000D03*
X144595Y629257D03*
X139095Y620408D03*
Y623608D03*
X150850Y574350D03*
X134941Y669690D03*
X135095Y694484D03*
X176492Y636617D03*
X180308D03*
X134941Y675114D03*
X135095Y688114D03*
X171895Y639429D03*
X148095Y636181D03*
Y642480D03*
Y651929D03*
Y661378D03*
Y667677D03*
Y677126D03*
Y686575D03*
Y696023D03*
X171595Y684429D03*
Y689429D03*
X140000Y654000D03*
X148000Y648000D03*
X173095Y650354D03*
X180000Y640906D03*
X176800D03*
X144595Y633657D03*
Y679650D03*
Y684050D03*
Y698548D03*
Y702948D03*
X139095Y670802D03*
Y674002D03*
Y689699D03*
Y692899D03*
X173000Y655200D03*
X134993Y707280D03*
X124966Y775525D03*
X125500Y719000D03*
X180000Y720000D03*
X136100Y775600D03*
X139600D03*
X147100D03*
X143600D03*
X145800Y737100D03*
X131400Y738200D03*
X134993Y713114D03*
X148095Y705472D03*
Y714921D03*
Y724370D03*
X173000Y718000D03*
X131400Y741700D03*
X122445Y743800D03*
X117945D03*
X144595Y717446D03*
Y721846D03*
X139095Y708597D03*
Y711797D03*
X171595Y714429D03*
X148600Y818700D03*
X147100Y814200D03*
X119534Y810975D03*
X116000Y814500D03*
X122251Y842400D03*
X156800Y816000D03*
X126800Y842500D03*
X143800Y807400D03*
X160000Y880000D03*
X140000Y900000D03*
X182000Y949000D03*
X180000Y980000D03*
X167000Y945909D03*
Y935909D03*
X178000Y960000D03*
X162200Y988000D03*
X161095Y980622D03*
X167000Y939309D03*
Y942509D03*
X174500Y960000D03*
X157200Y950800D03*
X155900Y954200D03*
X157000Y957500D03*
X161200Y946100D03*
X161700Y950800D03*
X135095Y1030914D03*
X180000Y1000000D03*
X176492Y1042129D03*
X180308D03*
X135095Y1024126D03*
X171595Y1014941D03*
X148095Y1022795D03*
X171595Y1029941D03*
X148095Y1032244D03*
X171595Y1044941D03*
X148095Y1041693D03*
Y1047992D03*
Y1057441D03*
Y1066890D03*
X140000Y1059500D03*
X129000Y1051500D03*
X173095Y1055866D03*
X148000Y1053500D03*
X180000Y1046418D03*
X176800D03*
X144595Y1034769D03*
Y1039169D03*
X139095Y1025920D03*
Y1029120D03*
X137500Y1014500D03*
X173000Y1060400D03*
X139300Y1067000D03*
X134941Y1075202D03*
X135095Y1099996D03*
X135001Y1112792D03*
X180000Y1140000D03*
X129500Y1084500D03*
X122500Y1107000D03*
X123500Y1123500D03*
X180000Y1120000D03*
Y1100000D03*
Y1080000D03*
X147800Y1140000D03*
X134941Y1080626D03*
X135095Y1093626D03*
X135001Y1118626D03*
X148095Y1073189D03*
Y1082638D03*
Y1092087D03*
Y1101535D03*
Y1110984D03*
Y1120433D03*
Y1129882D03*
X171595Y1089941D03*
Y1094941D03*
X173000Y1123500D03*
X144595Y1085162D03*
Y1089562D03*
Y1104060D03*
Y1108460D03*
Y1122958D03*
Y1127358D03*
X139095Y1076314D03*
Y1079514D03*
Y1095211D03*
Y1098411D03*
Y1114109D03*
Y1117309D03*
X171595Y1119941D03*
X124100Y1181025D03*
X143500Y1180400D03*
X147000D03*
X139500D03*
X136000D03*
X131500Y1143200D03*
Y1146700D03*
X122400Y1149200D03*
X117900D03*
X146700Y1219600D03*
X119534Y1216475D03*
X157325Y1223850D03*
X120000Y1280000D03*
X140000D03*
X160000D03*
X180000D03*
X120000Y1220000D03*
X180000D03*
X118250Y1252050D03*
X158052Y1216052D03*
X129150Y1252050D03*
X179147Y1353048D03*
X160000Y1340000D03*
X180000D03*
X140000D03*
Y1300000D03*
X160000D03*
X180000D03*
X129500Y1352321D03*
Y1340521D03*
X147956Y1347802D03*
X129500Y1344821D03*
Y1348021D03*
X154709Y1344513D03*
X121320Y1425396D03*
X117690Y1397168D03*
X143087Y1403623D03*
X180000Y1400000D03*
Y1420000D03*
X135095Y1429638D03*
X171595Y1420453D03*
X148095Y1428307D03*
X160000Y1360000D03*
X151125Y1376608D03*
X140125Y1381300D03*
X167301Y1363238D03*
Y1366838D03*
X158875Y1376100D03*
X135095Y1436426D03*
X134935Y1480714D03*
X126916Y1447364D03*
X180000Y1440000D03*
Y1500000D03*
X176492Y1447634D03*
X180308D03*
X134935Y1486138D03*
X135095Y1499138D03*
X171595Y1435453D03*
X148095Y1437756D03*
X171895Y1450453D03*
X148095Y1447205D03*
Y1453504D03*
Y1462953D03*
Y1472402D03*
Y1478701D03*
Y1488150D03*
Y1497599D03*
X171595Y1495453D03*
Y1500453D03*
X130000Y1470000D03*
X122000D03*
X114000D03*
X140000Y1464000D03*
X118000Y1470000D03*
X148000Y1458000D03*
X126000Y1466000D03*
X173095Y1461378D03*
X180000Y1451930D03*
X176800D03*
X144595Y1440281D03*
Y1444681D03*
Y1490674D03*
Y1495074D03*
X139095Y1431432D03*
Y1434632D03*
Y1481826D03*
Y1485026D03*
Y1500723D03*
X148095Y1468752D03*
X173100Y1466300D03*
X135095Y1505508D03*
X134995Y1518304D03*
X147700Y1545500D03*
X123400Y1522600D03*
X116500Y1505500D03*
X180000Y1520000D03*
X130600Y1549100D03*
X134995Y1524138D03*
X148095Y1507047D03*
Y1516496D03*
Y1525945D03*
Y1535394D03*
X173000Y1529000D03*
X123500Y1505200D03*
X144200Y1545500D03*
X128250Y1506500D03*
X144595Y1509572D03*
Y1513972D03*
Y1528470D03*
Y1532870D03*
X139095Y1503923D03*
Y1519621D03*
Y1522821D03*
X171595Y1525453D03*
X143500Y1625500D03*
X119534Y1621975D03*
X113841Y1580900D03*
X153700Y1633600D03*
X181500Y1641500D03*
X182500Y1622500D03*
X172000Y1595000D03*
X171500Y1613500D03*
X143300Y1586900D03*
X146800D03*
X138800Y1585100D03*
X135300D03*
X150200Y1628000D03*
X160200Y1710300D03*
X117300Y1696500D03*
X136600Y1681900D03*
X121700Y1654800D03*
X143000Y1656000D03*
X137000Y1666500D03*
X120000Y1678000D03*
X123000Y1702000D03*
X136700Y1720100D03*
X160000Y1720000D03*
Y1700000D03*
X180000D03*
Y1680000D03*
X113200Y1659800D03*
Y1656300D03*
X117000Y1654600D03*
X126900Y1654700D03*
X144400Y1720400D03*
X159800Y1730000D03*
X148000Y1787000D03*
X125000Y1757834D03*
Y1746034D03*
X177717Y1778162D03*
X180075Y1790692D03*
X125000Y1750334D03*
Y1753534D03*
X136500Y1733000D03*
X137000Y1727500D03*
X140825Y1729825D03*
X157898Y1780145D03*
X140300Y1724100D03*
X147200Y1724400D03*
X135065Y1835438D03*
X128800Y1854000D03*
X145500Y1807500D03*
X136500Y1811500D03*
X140000Y1820000D03*
X160000Y1800000D03*
X180000D03*
Y1840000D03*
X180308Y1853146D03*
X176492D03*
X135065Y1841650D03*
X171595Y1825965D03*
X148095Y1833819D03*
X171595Y1840965D03*
X148095Y1843268D03*
X171595Y1855965D03*
X148095Y1852717D03*
Y1859016D03*
X173095Y1866890D03*
X148000Y1864000D03*
X180000Y1857442D03*
X176800D03*
X144595Y1850193D03*
Y1845793D03*
X139095Y1840144D03*
Y1836944D03*
X151452Y1810000D03*
X134895Y1905020D03*
X128800Y1921300D03*
X129500Y1883500D03*
X115228Y1879770D03*
X128200Y1900300D03*
X180000Y1880000D03*
Y1900000D03*
Y1940000D03*
X134895Y1886150D03*
Y1891650D03*
Y1910650D03*
X134995Y1923650D03*
Y1929650D03*
X148095Y1868465D03*
Y1877914D03*
Y1884213D03*
Y1893662D03*
Y1903111D03*
Y1912559D03*
Y1922008D03*
Y1931457D03*
X171595Y1900965D03*
Y1905965D03*
X173000Y1934500D03*
X140000Y1870000D03*
X144595Y1900586D03*
Y1896186D03*
Y1919484D03*
Y1915084D03*
Y1938382D03*
Y1933982D03*
X139095Y1890538D03*
Y1887338D03*
Y1909435D03*
Y1906235D03*
Y1928333D03*
Y1925133D03*
X171595Y1930965D03*
X113500Y1875970D03*
X173500Y1871700D03*
X133000Y1977100D03*
X114200Y1974100D03*
X118500Y1971400D03*
X139100Y1977100D03*
X172559Y1986626D03*
X152559D03*
X132559D03*
X148095Y1940906D03*
X123200Y1947250D03*
X130500Y1946200D03*
X137300Y1969900D03*
X136800Y1959900D03*
X150800Y1958900D03*
X150600Y1970300D03*
X196665Y35585D03*
X205625Y38750D03*
X240000Y20000D03*
Y40000D03*
X230018Y5500D03*
X250018D03*
X190018D03*
X210018D03*
X208150Y32250D03*
X220000Y80000D03*
X240000D03*
X200000D03*
X220500Y67500D03*
X240000Y140000D03*
X220000D03*
Y160000D03*
X240000D03*
X200000Y180000D03*
X220000D03*
X240000D03*
X198800Y162500D03*
Y167000D03*
X194500Y236902D03*
X200000Y200000D03*
X240000Y220000D03*
X220000D03*
Y200000D03*
X240000D03*
X200000Y260000D03*
X240000D03*
X220000D03*
X194500Y243300D03*
X190500Y238501D03*
Y241701D03*
X200000Y280000D03*
X220000D03*
X240000D03*
Y320000D03*
Y300000D03*
X220000D03*
X200000D03*
Y320000D03*
X220000D03*
X240000Y340000D03*
X220000Y360000D03*
X240000D03*
X220000Y340000D03*
X200000D03*
Y360000D03*
X220000Y480000D03*
X200000D03*
X220000Y460000D03*
X200000D03*
X220000Y420000D03*
X200000Y440000D03*
Y420000D03*
Y520000D03*
X220000D03*
X195500Y531250D03*
Y546250D03*
Y538750D03*
X188854Y527099D03*
Y530902D03*
X206500Y538750D03*
Y546250D03*
Y531250D03*
X220000Y620000D03*
X240000Y600000D03*
Y580000D03*
X200000D03*
X195250Y576700D03*
X200250Y572100D03*
X190500Y639713D03*
X200000Y700000D03*
X220000D03*
Y680000D03*
X200000D03*
Y660000D03*
X220000D03*
Y640000D03*
X190500Y651513D03*
Y644013D03*
Y647213D03*
X240000Y760000D03*
X220000Y720000D03*
Y740000D03*
X200000Y760000D03*
Y740000D03*
Y720000D03*
X214700Y784200D03*
X200000Y900000D03*
X240000Y860000D03*
X220000D03*
Y880000D03*
X240000D03*
X190330Y913530D03*
X194200Y985900D03*
X220000Y940000D03*
X240000D03*
X201125Y957200D03*
X195500Y949750D03*
X207350Y968627D03*
X198900Y974000D03*
Y978500D03*
X229500Y946600D03*
X198900Y965477D03*
X208875Y957200D03*
X190600Y1045226D03*
X220000Y1040000D03*
Y1020000D03*
X240000D03*
Y1000000D03*
Y1060000D03*
X220000D03*
X240000Y1040000D03*
X190600Y1057024D03*
X190500Y1049525D03*
Y1052725D03*
X200000Y1080000D03*
Y1100000D03*
Y1140000D03*
Y1120000D03*
X220000Y1140000D03*
Y1120000D03*
X240000D03*
Y1100000D03*
X220000D03*
Y1080000D03*
X240000D03*
X255674Y1099470D03*
X196000Y1070300D03*
X208500Y1190000D03*
X200000Y1200000D03*
X240000D03*
Y1180000D03*
X200000Y1160000D03*
Y1280000D03*
X220000D03*
X240000D03*
Y1220000D03*
X220000D03*
X200000Y1340000D03*
X220000D03*
X240000D03*
X200000Y1300000D03*
X220000D03*
X240000D03*
X227000Y1359500D03*
X215000Y1368000D03*
X240000Y1367500D03*
Y1420000D03*
Y1400000D03*
X193400Y1377500D03*
Y1382000D03*
X190400Y1462536D03*
X240000Y1460000D03*
Y1440000D03*
X200000D03*
Y1460000D03*
Y1480000D03*
X240000D03*
Y1500000D03*
X200000D03*
X190400Y1450738D03*
X214500Y1459000D03*
X190500Y1455037D03*
Y1458237D03*
X202000Y1534000D03*
X200000Y1520000D03*
X220000D03*
X240000D03*
X200000Y1560000D03*
X220000D03*
X240000D03*
X203500Y1618500D03*
X229500Y1614500D03*
X189300Y1577200D03*
X220000Y1580000D03*
X248500Y1713005D03*
Y1716808D03*
X242500Y1702500D03*
X251800Y1718400D03*
X220000Y1720000D03*
X200000Y1660000D03*
Y1680000D03*
X220000D03*
Y1660000D03*
X240000Y1680000D03*
Y1660000D03*
X220200Y1740900D03*
X206000Y1735000D03*
X256000Y1745500D03*
X220000Y1734500D03*
X207600Y1777500D03*
X220800Y1763750D03*
X191353Y1772940D03*
X251900Y1769900D03*
X203299Y1763350D03*
X197900Y1786000D03*
Y1790500D03*
X222500Y1776200D03*
X255495Y1738573D03*
X251692D03*
X203299Y1759750D03*
X224875Y1768100D03*
X194620Y1859298D03*
X200000Y1800000D03*
X220000D03*
X240000D03*
X220000Y1840000D03*
X240000D03*
X194620Y1865000D03*
X190500Y1860549D03*
Y1863749D03*
X200000Y1880000D03*
Y1900000D03*
X220000D03*
X240000Y1920000D03*
X220000D03*
X200000D03*
Y1940000D03*
X220000D03*
X240000D03*
X256549Y1898366D03*
X240000Y1880000D03*
X256500D03*
X200000Y1980000D03*
Y1960000D03*
X220000Y1980000D03*
Y1960000D03*
X240000Y1980000D03*
Y1960000D03*
X252559Y1986626D03*
X232559D03*
X212559D03*
X192559D03*
X300000Y40000D03*
Y20000D03*
X320000D03*
Y40000D03*
X260000D03*
Y20000D03*
X280000D03*
Y40000D03*
X310018Y5500D03*
X330018D03*
X270018D03*
X290018D03*
X320000Y80000D03*
X300000Y60000D03*
X320000D03*
Y120000D03*
X300000D03*
X280000D03*
X260000Y100000D03*
X280000D03*
X300000D03*
X320000D03*
X300000Y80000D03*
X280000D03*
X260000D03*
Y160000D03*
X320000D03*
X300000Y140000D03*
X320000D03*
X260000Y180000D03*
X280000D03*
X292600Y166955D03*
X280000Y220000D03*
X260000D03*
Y200000D03*
X280000D03*
X300000D03*
Y220000D03*
X320000D03*
Y240000D03*
Y320000D03*
X300000D03*
X280000D03*
X260000D03*
X320000Y280000D03*
X300000D03*
X260000Y300000D03*
X318656Y391440D03*
X326156D03*
X280000Y360000D03*
X260000D03*
Y340000D03*
X280000D03*
X300000D03*
X320000D03*
X304553Y374081D03*
X313500Y386000D03*
X309000Y365000D03*
X313500Y362000D03*
X320000Y359500D03*
X327500Y373000D03*
X305100Y407700D03*
X315000Y412000D03*
X321400Y404400D03*
X327500Y377000D03*
X321500Y408500D03*
X312500Y393050D03*
X304400Y416200D03*
X280000Y460000D03*
Y480000D03*
X300000D03*
Y460000D03*
X320000D03*
X300000Y440000D03*
X280000D03*
Y420000D03*
X260000D03*
Y440000D03*
Y480000D03*
Y460000D03*
X321500Y413000D03*
X313200Y427500D03*
X317000D03*
X321500Y425200D03*
Y417000D03*
Y421000D03*
X260000Y520000D03*
X320000Y540000D03*
X296470Y555500D03*
X292667D03*
X297300Y505017D03*
X260000Y560000D03*
Y600000D03*
X280000Y620000D03*
X260000D03*
X302500Y583000D03*
X297500D03*
Y588000D03*
X302500D03*
X300000Y585500D03*
X288000Y586484D03*
X313000Y559000D03*
X329600Y583200D03*
X273500Y597000D03*
Y589000D03*
Y585000D03*
Y577000D03*
X284000Y612000D03*
X273500Y573000D03*
Y565000D03*
X286130Y615700D03*
X270000Y579030D03*
X310030Y615500D03*
X298030Y621000D03*
X269800Y590930D03*
X270000Y567130D03*
X289933Y615700D03*
X270000Y582833D03*
X313833Y615500D03*
X301833Y621000D03*
X269800Y594733D03*
X270000Y570933D03*
X298500Y660200D03*
Y680200D03*
X320000Y700000D03*
X260000D03*
X320000Y640000D03*
X300000D03*
X280000D03*
X260000D03*
X298200Y720000D03*
X260000D03*
X320000D03*
X326167Y811099D03*
Y814902D03*
X304400Y846700D03*
X321500Y807000D03*
X297840Y804552D03*
X280000Y820000D03*
X325053Y782652D03*
X309000Y795000D03*
X321500Y843000D03*
X323000Y819500D03*
X313500Y792000D03*
X320000Y789500D03*
X327500Y803000D03*
X304500Y836700D03*
X301300Y822550D03*
X321500Y847000D03*
X315000Y842000D03*
X321500Y838500D03*
X321400Y834400D03*
X327500Y807000D03*
X312000Y824500D03*
X260000Y860000D03*
Y880000D03*
X300000D03*
X280000D03*
Y860000D03*
X321500Y855200D03*
Y851000D03*
X317000Y857900D03*
X313200D03*
X260000Y940000D03*
X280000D03*
X300000D03*
X260000Y980000D03*
X280000D03*
X300000D03*
X320000Y1060000D03*
X300000D03*
X260000D03*
Y1040000D03*
X280000D03*
X300000D03*
X320000D03*
Y1020000D03*
X280000D03*
X300000D03*
X260000D03*
X280000Y1000000D03*
X300000D03*
X320000D03*
Y1140000D03*
X260000Y1120000D03*
X280000D03*
X300000D03*
X320000Y1100000D03*
X300000D03*
Y1080000D03*
X320000D03*
X260000Y1200000D03*
X280000D03*
Y1180000D03*
X260000Y1160000D03*
X296011Y1185470D03*
X309000Y1166500D03*
X295400Y1172655D03*
X313500Y1187500D03*
X320000Y1161000D03*
X327500Y1174500D03*
X305200Y1208300D03*
X321400Y1205900D03*
X321500Y1210000D03*
X327500Y1178500D03*
X312500Y1194000D03*
X304500Y1217500D03*
X320000Y1280000D03*
X300000Y1240000D03*
X320000Y1260000D03*
X300000Y1280000D03*
Y1260000D03*
X280000Y1280000D03*
X260000D03*
Y1260000D03*
X280000D03*
Y1220000D03*
X260000D03*
X321500Y1214500D03*
X321600Y1226600D03*
X313200Y1228800D03*
X317000D03*
X314437Y1213382D03*
X321500Y1222500D03*
Y1218500D03*
X280000Y1340000D03*
X260000D03*
X300000Y1300000D03*
X280000D03*
X260000D03*
X287167Y1380000D03*
X290970D03*
X311500Y1389000D03*
X280000Y1380000D03*
X260000Y1400000D03*
Y1420000D03*
X300000Y1421500D03*
X302500Y1424000D03*
X297500D03*
Y1419000D03*
X302500D03*
X303500Y1389000D03*
X297600Y1392000D03*
X273500Y1407500D03*
X319500Y1389000D03*
X301400Y1401500D03*
X315500Y1389000D03*
X293100Y1383500D03*
X284900D03*
X273500Y1419500D03*
Y1411500D03*
Y1423500D03*
X326500Y1417500D03*
Y1425700D03*
Y1405400D03*
Y1413500D03*
Y1429700D03*
X273500Y1403500D03*
X307500Y1389000D03*
X330000Y1423470D03*
X270100Y1425697D03*
X330300Y1411100D03*
X270000Y1413530D03*
X330000Y1419667D03*
X270100Y1429500D03*
X330300Y1407297D03*
X270000Y1417333D03*
X260000Y1440000D03*
X300984Y1433500D03*
X273500Y1431500D03*
X287600Y1448000D03*
X279650D03*
X299600D03*
X291600D03*
X326500Y1437700D03*
X311600Y1448000D03*
X303600D03*
X330000Y1435170D03*
X293830Y1451500D03*
X305830Y1451300D03*
X282030Y1451400D03*
X330000Y1431367D03*
X297633Y1451500D03*
X309633Y1451300D03*
X285833Y1451400D03*
X260000Y1520000D03*
X280000D03*
X300000D03*
X320000Y1540000D03*
Y1560000D03*
X300000D03*
X280000D03*
X260000D03*
X258585Y1508386D03*
X260000Y1620000D03*
Y1600000D03*
X300000Y1620000D03*
X280000Y1600000D03*
Y1620000D03*
X300000Y1600000D03*
X320000D03*
X318156Y1692440D03*
X325656D03*
X289300Y1696200D03*
Y1701800D03*
X292200Y1688900D03*
X295800D03*
X306200Y1689400D03*
X259000Y1702500D03*
X260000Y1680000D03*
Y1660000D03*
X321500Y1713000D03*
X327500Y1673000D03*
X305300Y1715700D03*
X306200Y1709600D03*
X301800Y1722100D03*
X265500Y1722000D03*
X283500D03*
X285000Y1700600D03*
X295600Y1693400D03*
X285000Y1697400D03*
X292400Y1693400D03*
X315000Y1712000D03*
X321500Y1721000D03*
X327500Y1677000D03*
X321500Y1717000D03*
Y1708500D03*
X321400Y1704400D03*
X313500Y1692500D03*
X320000Y1760000D03*
Y1780000D03*
X260000Y1740000D03*
X288000Y1742500D03*
X293000D03*
X284000Y1731250D03*
X268800Y1774600D03*
X276402Y1726146D03*
X272599D03*
X297000Y1777000D03*
Y1752000D03*
X302000D03*
X321500Y1725200D03*
X317000Y1727300D03*
X313200D03*
X260000Y1800000D03*
Y1840000D03*
X280000D03*
X320000Y1860000D03*
X300000D03*
Y1840000D03*
X320000Y1820000D03*
Y1840000D03*
X271500Y1795000D03*
X279500D03*
X287500D03*
X300000Y1800000D03*
X320000Y1940000D03*
X300000D03*
X280000D03*
X260000D03*
X280071Y1924667D03*
X300000Y1900000D03*
Y1920000D03*
X320000D03*
Y1900000D03*
X300000Y1880000D03*
X320000D03*
X260000Y1980000D03*
Y1960000D03*
X280000Y1980000D03*
Y1960000D03*
X300000Y1980000D03*
Y1960000D03*
X320000Y1980000D03*
Y1960000D03*
X312559Y1986626D03*
X292559D03*
X272559D03*
X380000Y20000D03*
Y40000D03*
X400000D03*
Y20000D03*
X340000Y40000D03*
Y20000D03*
X360000Y40000D03*
Y20000D03*
X390018Y5500D03*
X350018D03*
X370018D03*
X400000Y100000D03*
Y80000D03*
X377500Y98000D03*
X400000Y60000D03*
X340000Y80000D03*
Y100000D03*
Y60000D03*
X400000Y120000D03*
X340000D03*
X373500Y98000D03*
X363750Y65250D03*
X352500Y68500D03*
X358500Y93500D03*
X374300Y81400D03*
X363750Y73300D03*
X378100Y81500D03*
X382200D03*
X382000Y98000D03*
X358000Y64000D03*
X344500Y71750D03*
X340000Y180000D03*
X360000D03*
X380000D03*
X400000D03*
Y140000D03*
Y160000D03*
X380000Y140000D03*
Y160000D03*
X360000Y140000D03*
Y160000D03*
X340000D03*
Y140000D03*
X357250Y124000D03*
X360750D03*
X400000Y220000D03*
Y200000D03*
X380000D03*
X340000Y240000D03*
Y260000D03*
X360000D03*
Y280000D03*
X370000Y411000D03*
Y405500D03*
X375500D03*
X381000D03*
X375500Y411000D03*
X381000D03*
X359000D03*
X364500D03*
Y405500D03*
X359000D03*
X370000Y400000D03*
X381000D03*
X375500D03*
X370000Y389000D03*
Y394500D03*
X375500D03*
Y389000D03*
X381000D03*
Y394500D03*
X364500Y400000D03*
X365000Y394500D03*
Y389000D03*
X359000D03*
Y394500D03*
Y400000D03*
X370128Y361337D03*
X349706Y355693D03*
X356250Y349000D03*
X337500Y406250D03*
X331500Y393000D03*
X368500Y364500D03*
X372000D03*
X401500Y401500D03*
X397000Y383750D03*
X383750Y349000D03*
X391800Y355800D03*
X331500Y389000D03*
X365100Y371200D03*
X397000Y380250D03*
X375200Y371250D03*
X349870Y348870D03*
X331300Y408500D03*
X400000Y440000D03*
Y460000D03*
Y480000D03*
X339500Y416750D03*
X370397Y439122D03*
X368500Y436000D03*
X372000D03*
X397000Y414750D03*
X379250Y451000D03*
X385896Y444265D03*
X343750Y451000D03*
X350241Y444377D03*
X364758Y429249D03*
X375200Y429250D03*
X350137Y451250D03*
X385607Y451232D03*
X400000Y540000D03*
X340000D03*
X380000Y500000D03*
Y540000D03*
X400000Y520000D03*
X339500Y572667D03*
Y576470D03*
X400000Y560000D03*
X332500Y597000D03*
Y589000D03*
X360000Y580000D03*
X340000Y560000D03*
Y600000D03*
Y620000D03*
X380000D03*
X400000D03*
X380000Y560000D03*
X332500Y605000D03*
X380000Y660000D03*
X400000Y640000D03*
Y680000D03*
Y700000D03*
X340000Y660000D03*
Y680000D03*
Y700000D03*
X360000D03*
Y680000D03*
Y660000D03*
Y640000D03*
X380000D03*
X400000Y740000D03*
Y720000D03*
X340000Y740000D03*
Y720000D03*
X360000D03*
X400000Y780000D03*
X340000D03*
X370000Y841000D03*
Y835500D03*
X375500D03*
X381000D03*
X375500Y841000D03*
X381000D03*
X359000D03*
X364500D03*
Y835500D03*
X359000D03*
X370000Y830000D03*
X381000D03*
X375500D03*
X370000Y819000D03*
Y824500D03*
X375500D03*
Y819000D03*
X381000D03*
Y824500D03*
X364500Y830000D03*
X365000Y824500D03*
Y819000D03*
X359000D03*
Y824500D03*
Y830000D03*
X362000Y797000D03*
X365500D03*
X358000Y794000D03*
X397000Y844750D03*
X339500Y846750D03*
X337500Y836250D03*
X331500Y823000D03*
X401500Y836000D03*
X377250Y779000D03*
X385250Y785700D03*
X395000Y806500D03*
X331500Y819000D03*
X358800Y803600D03*
X368700Y803750D03*
X388250Y803300D03*
X385196Y779112D03*
X331300Y838500D03*
X402000Y844000D03*
X360100Y808080D03*
X371059Y903347D03*
X355622Y919857D03*
X380000Y920000D03*
X400000D03*
Y900000D03*
X368500Y865000D03*
X372000D03*
X379228Y874277D03*
X387250Y881000D03*
X351740Y880717D03*
X343749Y874298D03*
X360800Y858500D03*
X375200Y858250D03*
X343894Y880707D03*
X379372Y880728D03*
X335823Y940330D03*
X340000Y980000D03*
X360000D03*
X380000D03*
X400000D03*
Y960000D03*
X380000D03*
X340000D03*
X360000D03*
Y940000D03*
X380000D03*
X400000D03*
Y1060000D03*
X380000D03*
X400000Y1040000D03*
X380000D03*
X360000Y1060000D03*
X340000D03*
X360000Y1040000D03*
X340000D03*
Y1000000D03*
Y1020000D03*
X360000Y1000000D03*
Y1020000D03*
X380000Y1000000D03*
Y1020000D03*
X400000Y1000000D03*
Y1020000D03*
X360000Y1140000D03*
X340000D03*
X380000Y1100000D03*
X400000Y1080000D03*
X380000D03*
X360000Y1100000D03*
X340000D03*
X360000Y1080000D03*
X340000D03*
Y1160000D03*
X354228Y1164233D03*
X370000Y1212500D03*
Y1207000D03*
X375500D03*
X381000D03*
X375500Y1212500D03*
X381000D03*
X359000D03*
X364500D03*
Y1207000D03*
X359000D03*
X370000Y1201500D03*
X381000D03*
X375500D03*
X370000Y1190500D03*
Y1196000D03*
X375500D03*
Y1190500D03*
X381000D03*
Y1196000D03*
X364500Y1201500D03*
X365000Y1196000D03*
Y1190500D03*
X359000D03*
Y1196000D03*
Y1201500D03*
X337500Y1207750D03*
X331500Y1194500D03*
X371000Y1168000D03*
X367500D03*
X363500Y1165000D03*
X402000Y1202500D03*
X383750Y1150500D03*
X391765Y1157852D03*
X396750Y1181250D03*
X331500Y1190500D03*
X364300Y1174900D03*
X374200Y1174750D03*
X391900Y1150250D03*
X331300Y1210000D03*
X398750Y1188250D03*
X359175Y1179640D03*
X400000Y1280000D03*
Y1260000D03*
X339500Y1218250D03*
X370200Y1239700D03*
X368500Y1236500D03*
X372000D03*
X343749Y1245719D03*
X351771Y1252213D03*
X379249Y1245782D03*
X387208Y1252212D03*
X391500Y1218500D03*
X365200Y1229800D03*
X400700Y1237500D03*
X375200Y1229750D03*
X343822Y1252222D03*
X379395Y1252274D03*
X400000Y1340000D03*
X380000D03*
Y1320000D03*
X400000D03*
X380000Y1300000D03*
X400000D03*
X360000Y1340000D03*
Y1320000D03*
X340000Y1340000D03*
X380000Y1420000D03*
Y1400000D03*
X400000Y1420000D03*
Y1400000D03*
Y1380000D03*
Y1360000D03*
X380000D03*
Y1380000D03*
X360000D03*
Y1360000D03*
X340000D03*
Y1380000D03*
X380000Y1500000D03*
X360000D03*
X340000Y1480000D03*
Y1460000D03*
X400000D03*
X380000Y1440000D03*
X400000D03*
X360000Y1560000D03*
X400000Y1540000D03*
X380000D03*
X360000D03*
Y1520000D03*
X380000D03*
X400000D03*
Y1580000D03*
X380000D03*
X348250Y1649000D03*
X356247Y1644123D03*
X348257Y1644132D03*
X356174Y1649291D03*
X334500Y1650000D03*
Y1665000D03*
X380000Y1660000D03*
X400000D03*
X359000Y1705500D03*
Y1700000D03*
Y1694500D03*
Y1689000D03*
X365000D03*
Y1694500D03*
X364500Y1700000D03*
Y1705500D03*
Y1711000D03*
X359000D03*
X381000D03*
X375500D03*
X381000Y1705500D03*
X375500D03*
X381000Y1694500D03*
Y1689000D03*
X375500D03*
Y1694500D03*
X370000D03*
Y1689000D03*
Y1705500D03*
Y1711000D03*
X381000Y1700000D03*
X375500D03*
X370000D03*
X402000Y1701000D03*
X339500Y1716750D03*
X337500Y1706250D03*
X331500Y1695000D03*
X368500Y1664000D03*
X372500Y1667000D03*
X376000D03*
X388750Y1673000D03*
X356238Y1655722D03*
X331500Y1691000D03*
X369100Y1673700D03*
X385250Y1673000D03*
X331500Y1708500D03*
X395500Y1690500D03*
X376890Y1678000D03*
X368500Y1768000D03*
X400000Y1760000D03*
X365400Y1734400D03*
X369000Y1734500D03*
X372500D03*
X393000Y1723500D03*
X351750Y1751000D03*
X343709Y1744187D03*
X376808Y1755434D03*
X373005D03*
X379000Y1736000D03*
X351750Y1755500D03*
X343750D03*
X383000Y1736300D03*
X365700Y1727700D03*
X383000Y1728700D03*
X375700Y1727750D03*
X343668Y1750741D03*
X379000Y1726000D03*
X400000Y1860000D03*
X380000D03*
X360000D03*
X340000D03*
Y1800000D03*
Y1840000D03*
X360000D03*
X380000D03*
X400000D03*
Y1820000D03*
X380000D03*
X360000D03*
X340000D03*
X360000Y1800000D03*
X400000D03*
X380000D03*
X400000Y1940000D03*
X380000D03*
X360000D03*
X340000D03*
Y1900000D03*
Y1920000D03*
X360000D03*
Y1900000D03*
X380000D03*
Y1920000D03*
X400000D03*
Y1900000D03*
X340000Y1880000D03*
X360000D03*
X380000D03*
X400000D03*
X340000Y1980000D03*
Y1960000D03*
X360000Y1980000D03*
Y1960000D03*
X380000Y1980000D03*
Y1960000D03*
X400000Y1980000D03*
Y1960000D03*
X392559Y1986626D03*
X372559D03*
X352559D03*
X332559D03*
X460000Y20000D03*
Y40000D03*
X420000Y20000D03*
Y40000D03*
X440000D03*
Y20000D03*
X470018Y5500D03*
X410018D03*
X430018D03*
X450018D03*
X460000Y100000D03*
X420000D03*
X440000D03*
X460000Y80000D03*
Y60000D03*
X440000D03*
Y80000D03*
X420000D03*
Y60000D03*
X460000Y120000D03*
X440000D03*
X420000D03*
Y180000D03*
X440000D03*
X460000D03*
Y140000D03*
Y160000D03*
X440000D03*
Y140000D03*
X420000D03*
Y160000D03*
Y200000D03*
X460000D03*
X440000D03*
X420000Y220000D03*
X440000D03*
X460000D03*
Y240000D03*
X440000D03*
X420000D03*
Y260000D03*
X440000D03*
X460000D03*
X440000Y280000D03*
X460000D03*
X440000Y320000D03*
X460000D03*
Y300000D03*
X440000Y400000D03*
X460000D03*
Y380000D03*
X440000D03*
Y360000D03*
X460000D03*
Y340000D03*
X440000D03*
X460000Y480000D03*
Y460000D03*
X440000Y480000D03*
Y460000D03*
Y440000D03*
X460000D03*
Y420000D03*
X440000D03*
X420000Y520000D03*
Y540000D03*
X440000D03*
Y520000D03*
X460000D03*
Y500000D03*
X420000D03*
Y620000D03*
X440000Y600000D03*
X460000Y580000D03*
X420000Y600000D03*
X440000Y580000D03*
X420000Y560000D03*
Y700000D03*
X460000Y660000D03*
Y680000D03*
Y700000D03*
X420000Y680000D03*
Y660000D03*
Y720000D03*
Y740000D03*
X460000Y720000D03*
Y760000D03*
X420000D03*
Y840000D03*
X440000D03*
X460000D03*
Y820000D03*
Y800000D03*
Y780000D03*
X420000D03*
X414281Y820751D03*
X421000Y812750D03*
X420722Y820627D03*
X420000Y920000D03*
X440000D03*
X460000D03*
Y900000D03*
X440000D03*
X420000D03*
Y880000D03*
X460000D03*
X440000D03*
X420000Y860000D03*
X440000D03*
X460000D03*
X420000Y980000D03*
X440000D03*
X460000D03*
Y960000D03*
X440000D03*
X420000D03*
Y940000D03*
X440000D03*
X460000D03*
X420000Y1060000D03*
X440000Y1040000D03*
X420000D03*
Y1000000D03*
Y1020000D03*
X440000Y1000000D03*
Y1020000D03*
X460000D03*
Y1000000D03*
X440000Y1120000D03*
X460000D03*
Y1080000D03*
X420000Y1200000D03*
X440000D03*
X460000D03*
Y1160000D03*
Y1180000D03*
X440000Y1160000D03*
Y1180000D03*
X420000Y1160000D03*
Y1180000D03*
Y1280000D03*
Y1240000D03*
X440000D03*
X460000D03*
Y1260000D03*
X440000D03*
X420000D03*
X460000Y1280000D03*
X440000D03*
X420743Y1215266D03*
X414274Y1223246D03*
X420763Y1223185D03*
X420000Y1340000D03*
Y1320000D03*
X440000D03*
Y1340000D03*
X460000D03*
Y1320000D03*
X440000Y1300000D03*
X420000D03*
X460000D03*
X440000Y1420000D03*
X420000D03*
Y1400000D03*
Y1380000D03*
Y1360000D03*
X440000Y1400000D03*
Y1360000D03*
Y1380000D03*
X460000D03*
Y1360000D03*
Y1420000D03*
Y1400000D03*
X440000Y1500000D03*
X420000Y1480000D03*
X440000D03*
Y1460000D03*
X420000D03*
Y1440000D03*
X440000D03*
X460000Y1500000D03*
Y1480000D03*
Y1460000D03*
Y1440000D03*
X420000Y1540000D03*
X460000Y1520000D03*
Y1580000D03*
X440000D03*
X420000D03*
Y1700000D03*
Y1680000D03*
Y1660000D03*
X440000Y1680000D03*
X460000D03*
Y1660000D03*
X421000Y1713750D03*
X414299Y1721750D03*
X425879Y1721724D03*
X425500Y1713750D03*
X420732Y1721757D03*
X420000Y1760000D03*
X406500Y1736500D03*
X440000Y1780000D03*
Y1760000D03*
X460000D03*
Y1780000D03*
X450000Y1803500D03*
X440000Y1860000D03*
X420000D03*
Y1840000D03*
X440000D03*
X420000Y1820000D03*
X460000Y1840000D03*
Y1860000D03*
Y1940000D03*
X440000D03*
X420000D03*
Y1900000D03*
Y1920000D03*
X440000D03*
Y1900000D03*
X460000Y1920000D03*
Y1900000D03*
X420000Y1880000D03*
X440000D03*
X460000D03*
X420000Y1980000D03*
Y1960000D03*
X440000Y1980000D03*
Y1960000D03*
X460000Y1980000D03*
Y1960000D03*
X472559Y1986626D03*
X452559D03*
X432559D03*
X412559D03*
X500000Y40000D03*
X480000D03*
X520000D03*
X530018Y5500D03*
X510018D03*
X490018D03*
X500000Y20000D03*
X480000D03*
X520000D03*
X540000Y40000D03*
Y20000D03*
Y100000D03*
X520000D03*
X500000D03*
X480000D03*
Y120000D03*
X500000D03*
X520000D03*
X480000Y60000D03*
Y80000D03*
X500000D03*
Y60000D03*
X520000D03*
Y80000D03*
X540000Y120000D03*
Y80000D03*
Y60000D03*
X480000Y140000D03*
Y160000D03*
X500000D03*
Y140000D03*
X520000D03*
Y160000D03*
Y180000D03*
X500000D03*
X480000D03*
X540000Y160000D03*
Y140000D03*
Y180000D03*
X520000Y260000D03*
X500000D03*
X520000Y240000D03*
X480000D03*
X500000D03*
Y220000D03*
X480000D03*
Y200000D03*
X500000D03*
X520000D03*
Y220000D03*
X540000Y260000D03*
Y220000D03*
Y240000D03*
Y200000D03*
X500000Y280000D03*
X520000D03*
X480000D03*
Y300000D03*
X500000D03*
X520000D03*
Y320000D03*
X500000D03*
X480000D03*
X540000Y280000D03*
Y300000D03*
Y320000D03*
X500000Y400000D03*
X520000D03*
Y380000D03*
X540000Y400000D03*
Y380000D03*
Y360000D03*
Y340000D03*
X480000Y400000D03*
Y340000D03*
X500000D03*
X520000D03*
Y360000D03*
X500000D03*
X480000D03*
Y380000D03*
Y440000D03*
X500000D03*
X480000Y420000D03*
X500000D03*
X520000D03*
X540000D03*
X520000Y480000D03*
X500000D03*
X480000D03*
Y460000D03*
X500000D03*
X520000D03*
Y440000D03*
X540000Y460000D03*
Y440000D03*
X500000Y500000D03*
X480000D03*
X520000Y520000D03*
X500000Y540000D03*
X540000D03*
X520000Y560000D03*
X540000D03*
Y580000D03*
X500000D03*
Y600000D03*
X520000D03*
X540000D03*
X520000Y580000D03*
X480000Y560000D03*
X540000Y700000D03*
X520000D03*
X500000D03*
X480000D03*
X540000Y680000D03*
X520000D03*
X500000D03*
X480000D03*
X540000Y660000D03*
X520000D03*
X500000D03*
X480000D03*
Y640000D03*
X500000D03*
X520000D03*
X540000D03*
X520000Y720000D03*
X500000D03*
X480000D03*
X540000Y740000D03*
X480000Y760000D03*
X500000D03*
X520000D03*
X540000D03*
X520000Y780000D03*
X500000D03*
X480000D03*
Y800000D03*
X500000D03*
X520000D03*
X480000Y820000D03*
X500000D03*
X520000D03*
X480000Y840000D03*
X500000D03*
X520000D03*
X540000D03*
Y780000D03*
Y800000D03*
Y820000D03*
X520000Y900000D03*
Y920000D03*
X500000D03*
X480000D03*
X520000Y860000D03*
X500000D03*
X480000D03*
Y880000D03*
X500000D03*
X520000D03*
X480000Y900000D03*
X500000D03*
X540000Y920000D03*
Y860000D03*
Y880000D03*
Y900000D03*
X520000Y980000D03*
X500000D03*
X480000D03*
X520000Y940000D03*
X500000D03*
X480000D03*
Y960000D03*
X500000D03*
X520000D03*
X540000Y980000D03*
Y940000D03*
Y960000D03*
X520000Y1060000D03*
X500000D03*
X480000D03*
Y1000000D03*
X500000Y1040000D03*
X520000D03*
X540000Y1060000D03*
Y1040000D03*
X480000Y1080000D03*
X500000D03*
X520000D03*
Y1120000D03*
X500000D03*
X480000D03*
X540000D03*
Y1100000D03*
X520000Y1200000D03*
X500000D03*
X480000D03*
Y1180000D03*
Y1160000D03*
X500000Y1180000D03*
Y1160000D03*
X520000Y1180000D03*
Y1160000D03*
X540000Y1180000D03*
Y1160000D03*
Y1200000D03*
X480000Y1280000D03*
X500000D03*
X520000D03*
X480000Y1260000D03*
X500000D03*
X520000D03*
X500000Y1240000D03*
X480000D03*
X540000Y1280000D03*
Y1220000D03*
X500000Y1340000D03*
X520000D03*
X480000D03*
Y1320000D03*
X500000D03*
X520000D03*
X480000Y1300000D03*
X500000D03*
X520000D03*
X540000Y1340000D03*
Y1320000D03*
Y1300000D03*
X520000Y1420000D03*
X500000D03*
X480000D03*
X520000Y1380000D03*
Y1400000D03*
X500000Y1380000D03*
Y1400000D03*
X480000Y1380000D03*
Y1400000D03*
X500000Y1360000D03*
X520000D03*
X480000D03*
X540000Y1420000D03*
Y1380000D03*
Y1400000D03*
Y1360000D03*
X520000Y1500000D03*
X500000D03*
X480000D03*
X520000Y1440000D03*
Y1460000D03*
Y1480000D03*
X500000Y1440000D03*
Y1460000D03*
Y1480000D03*
X480000Y1440000D03*
Y1460000D03*
Y1480000D03*
X540000Y1500000D03*
Y1440000D03*
Y1460000D03*
Y1480000D03*
X500000Y1560000D03*
X480000Y1520000D03*
X500000D03*
X520000D03*
X540000D03*
X480000Y1580000D03*
X540000Y1680000D03*
X520000D03*
X500000D03*
X480000D03*
Y1700000D03*
Y1660000D03*
Y1720000D03*
X500000D03*
X520000D03*
Y1700000D03*
X500000D03*
X520000Y1660000D03*
X500000D03*
X540000Y1700000D03*
Y1720000D03*
Y1660000D03*
Y1780000D03*
X520000Y1760000D03*
X480000Y1780000D03*
X500000D03*
X520000D03*
X480000Y1760000D03*
X500000D03*
X520000Y1740000D03*
X500000D03*
X480000D03*
X540000Y1760000D03*
Y1740000D03*
Y1820000D03*
Y1840000D03*
Y1860000D03*
X520000D03*
X480000D03*
X500000Y1840000D03*
X520000D03*
X500000Y1820000D03*
X480000D03*
X520000D03*
X540000Y1940000D03*
X500000D03*
X520000D03*
X480000D03*
X520000Y1920000D03*
X500000D03*
X480000D03*
X520000Y1900000D03*
X500000D03*
X480000D03*
Y1880000D03*
X500000D03*
X520000D03*
X540000Y1900000D03*
Y1880000D03*
Y1920000D03*
X492559Y1986626D03*
X512559D03*
X532559D03*
X520000Y1960000D03*
Y1980000D03*
X500000Y1960000D03*
Y1980000D03*
X480000Y1960000D03*
Y1980000D03*
X540000Y1960000D03*
Y1980000D03*
X580000Y40000D03*
X560000D03*
X600000D03*
X590018Y5500D03*
X570018D03*
X550018D03*
X580000Y20000D03*
X560000D03*
X600000D03*
X620000Y40000D03*
X610018Y5500D03*
X620000Y20000D03*
Y100000D03*
X600000D03*
X580000D03*
X560000D03*
Y120000D03*
X580000D03*
X600000D03*
X560000Y60000D03*
Y80000D03*
X580000D03*
Y60000D03*
X600000D03*
Y80000D03*
X620000Y120000D03*
Y80000D03*
Y60000D03*
X560000Y140000D03*
Y160000D03*
X580000D03*
Y140000D03*
X600000D03*
Y160000D03*
Y180000D03*
X580000D03*
X560000D03*
X620000Y160000D03*
Y140000D03*
Y180000D03*
X580000Y260000D03*
X600000D03*
X620000D03*
X560000D03*
X600000Y200000D03*
Y220000D03*
X580000D03*
Y200000D03*
X560000D03*
Y220000D03*
Y240000D03*
X580000D03*
X600000D03*
X620000D03*
Y220000D03*
Y200000D03*
X560000Y320000D03*
X580000D03*
X600000D03*
X620000D03*
X560000Y300000D03*
X580000D03*
X600000D03*
X620000D03*
X580000Y280000D03*
X600000D03*
X620000D03*
X560000D03*
X620000Y400000D03*
X600000D03*
X580000D03*
X560000D03*
Y380000D03*
X580000D03*
X600000D03*
X620000D03*
X560000Y360000D03*
X580000D03*
X600000D03*
X620000D03*
X560000Y340000D03*
X580000D03*
X600000D03*
X620000D03*
X600000Y480000D03*
X620000D03*
Y460000D03*
X580000Y440000D03*
X560000D03*
X620000Y420000D03*
X600000D03*
X580000D03*
X560000D03*
Y460000D03*
X620000Y520000D03*
X600000D03*
X580000D03*
Y500000D03*
X600000Y540000D03*
Y500000D03*
X620000D03*
X580000Y540000D03*
X560000D03*
X620000D03*
Y560000D03*
X580000D03*
X600000D03*
X560000D03*
Y580000D03*
X600000D03*
X620000Y600000D03*
X600000D03*
X580000D03*
Y580000D03*
X620000D03*
Y640000D03*
X600000D03*
X580000D03*
X560000D03*
X620000Y700000D03*
X600000D03*
X580000D03*
X560000D03*
X620000Y680000D03*
X600000D03*
X580000D03*
X560000D03*
X620000Y660000D03*
X600000D03*
X580000D03*
X560000D03*
Y740000D03*
X580000D03*
X600000D03*
X620000D03*
X580000Y760000D03*
X600000D03*
X620000D03*
X560000D03*
X580000Y780000D03*
X600000D03*
X620000D03*
X580000Y800000D03*
X600000D03*
X620000D03*
X580000Y820000D03*
X600000D03*
X620000D03*
X560000Y840000D03*
X580000D03*
X600000D03*
X560000Y780000D03*
Y800000D03*
X620000Y840000D03*
X600000Y920000D03*
X580000D03*
X560000D03*
X600000Y860000D03*
X580000D03*
X560000D03*
Y900000D03*
Y880000D03*
X580000D03*
Y900000D03*
X600000D03*
Y880000D03*
X620000Y920000D03*
Y880000D03*
Y900000D03*
Y860000D03*
X600000Y980000D03*
X580000D03*
X560000D03*
X580000Y940000D03*
X560000D03*
Y960000D03*
X580000D03*
X600000D03*
Y940000D03*
X620000D03*
Y960000D03*
Y980000D03*
X600000Y1060000D03*
X580000D03*
X560000D03*
Y1040000D03*
X580000D03*
X600000D03*
X620000D03*
Y1060000D03*
X560000Y1100000D03*
X580000D03*
X600000D03*
Y1120000D03*
X580000D03*
X560000D03*
X620000D03*
Y1100000D03*
X560000Y1180000D03*
X580000D03*
Y1160000D03*
X600000Y1180000D03*
Y1160000D03*
Y1200000D03*
X580000D03*
X560000D03*
X620000D03*
Y1160000D03*
Y1180000D03*
X580000Y1260000D03*
Y1240000D03*
X560000D03*
X600000Y1220000D03*
X580000D03*
X560000D03*
X600000Y1260000D03*
Y1240000D03*
X620000Y1280000D03*
Y1220000D03*
Y1240000D03*
Y1260000D03*
X560000Y1340000D03*
X580000D03*
X600000D03*
X560000Y1320000D03*
X580000D03*
X560000Y1300000D03*
X620000D03*
X600000Y1420000D03*
X580000D03*
X560000D03*
X600000Y1400000D03*
X580000Y1380000D03*
Y1400000D03*
X560000Y1380000D03*
Y1400000D03*
X580000Y1360000D03*
X600000D03*
X620000Y1420000D03*
Y1400000D03*
Y1380000D03*
Y1360000D03*
X600000Y1500000D03*
X580000D03*
X560000D03*
X600000Y1440000D03*
Y1460000D03*
Y1480000D03*
X580000Y1440000D03*
Y1460000D03*
Y1480000D03*
X560000Y1440000D03*
Y1460000D03*
Y1480000D03*
X620000Y1500000D03*
Y1480000D03*
Y1460000D03*
Y1440000D03*
X560000Y1520000D03*
X580000D03*
X620000Y1680000D03*
X560000D03*
X580000D03*
X600000D03*
Y1700000D03*
Y1720000D03*
X580000D03*
Y1700000D03*
X560000D03*
Y1720000D03*
X600000Y1660000D03*
X580000D03*
X560000D03*
X620000Y1700000D03*
Y1720000D03*
Y1660000D03*
Y1780000D03*
X600000D03*
X580000D03*
X560000D03*
X620000Y1760000D03*
X600000D03*
X580000D03*
X560000D03*
X620000Y1740000D03*
X600000D03*
X580000D03*
X560000D03*
Y1840000D03*
Y1860000D03*
X620000Y1800000D03*
X600000D03*
X580000D03*
X560000D03*
X620000Y1840000D03*
X600000D03*
X580000D03*
X620000Y1860000D03*
X600000D03*
X580000D03*
X560000Y1940000D03*
X580000D03*
X600000D03*
X620000D03*
X560000Y1880000D03*
X620000D03*
X600000D03*
X580000D03*
X620000Y1900000D03*
X600000D03*
X580000D03*
X620000Y1920000D03*
X600000D03*
X580000D03*
X560000D03*
Y1900000D03*
X620000Y1960000D03*
X600000D03*
X580000D03*
X552559Y1986626D03*
X572559D03*
X592559D03*
X600000Y1980000D03*
X580000D03*
X560000D03*
Y1960000D03*
X612559Y1986626D03*
X620000Y1980000D03*
X660000Y40000D03*
X640000D03*
X670018Y5500D03*
X650018D03*
X630018D03*
X660000Y20000D03*
X640000D03*
X680000D03*
Y40000D03*
X690018Y5500D03*
X680000Y100000D03*
X660000D03*
X640000D03*
Y120000D03*
X660000D03*
X640000Y60000D03*
Y80000D03*
X660000D03*
Y60000D03*
X680000Y120000D03*
Y60000D03*
Y80000D03*
X640000Y140000D03*
Y160000D03*
X660000D03*
Y140000D03*
Y180000D03*
X640000D03*
X680000Y140000D03*
Y160000D03*
Y180000D03*
X660000Y260000D03*
X640000D03*
Y240000D03*
X660000D03*
Y220000D03*
Y200000D03*
X640000Y220000D03*
Y200000D03*
X680000Y260000D03*
Y240000D03*
Y220000D03*
Y200000D03*
X640000Y320000D03*
X660000D03*
X680000D03*
X640000Y300000D03*
X660000D03*
X680000D03*
X640000Y280000D03*
X660000D03*
X680000D03*
X640000Y400000D03*
Y380000D03*
X660000D03*
X640000Y360000D03*
X660000D03*
X680000D03*
X640000Y340000D03*
X660000D03*
X680000D03*
Y480000D03*
Y460000D03*
Y440000D03*
X640000Y480000D03*
X660000D03*
Y460000D03*
X640000D03*
X660000Y440000D03*
X640000D03*
X680000Y420000D03*
X660000Y520000D03*
X640000D03*
X680000D03*
Y500000D03*
X640000D03*
X660000D03*
X640000Y540000D03*
X660000D03*
X680000D03*
Y560000D03*
X660000D03*
X640000D03*
X680000Y600000D03*
X660000D03*
X640000D03*
Y580000D03*
X660000D03*
X680000D03*
Y660000D03*
Y680000D03*
X640000Y640000D03*
Y700000D03*
X660000Y680000D03*
X640000D03*
X660000Y660000D03*
X640000D03*
X660000Y640000D03*
X680000D03*
X640000Y720000D03*
X660000D03*
X680000D03*
X640000Y740000D03*
X660000D03*
X680000D03*
X640000Y760000D03*
X660000D03*
X680000D03*
X640000Y780000D03*
X660000D03*
X680000D03*
X640000Y800000D03*
X660000D03*
X680000D03*
X640000Y820000D03*
X660000D03*
X680000D03*
X640000Y840000D03*
X660000D03*
X680000D03*
X640000Y920000D03*
X660000D03*
X640000Y900000D03*
X660000D03*
X640000Y880000D03*
X660000D03*
X640000Y860000D03*
X660000D03*
X680000Y920000D03*
Y900000D03*
Y880000D03*
Y860000D03*
X640000Y940000D03*
Y960000D03*
X660000D03*
Y980000D03*
X640000D03*
X680000D03*
Y960000D03*
X660000Y1040000D03*
X640000D03*
Y1060000D03*
X680000Y1040000D03*
X640000Y1100000D03*
Y1120000D03*
X660000D03*
Y1100000D03*
X680000D03*
Y1120000D03*
Y1080000D03*
X640000Y1200000D03*
X660000D03*
Y1160000D03*
X640000D03*
Y1180000D03*
X680000Y1160000D03*
Y1200000D03*
X640000Y1280000D03*
X660000D03*
Y1220000D03*
X640000D03*
Y1240000D03*
X660000D03*
X640000Y1260000D03*
X660000D03*
X680000Y1240000D03*
Y1260000D03*
Y1280000D03*
Y1220000D03*
X660000Y1340000D03*
X640000Y1300000D03*
X660000D03*
Y1320000D03*
X640000D03*
X680000Y1340000D03*
Y1300000D03*
Y1320000D03*
X660000Y1420000D03*
X640000D03*
Y1400000D03*
X660000D03*
X640000Y1380000D03*
X680000Y1420000D03*
Y1360000D03*
X660000Y1500000D03*
X640000D03*
X660000Y1480000D03*
X640000D03*
Y1460000D03*
Y1440000D03*
X660000D03*
X680000Y1500000D03*
Y1480000D03*
Y1440000D03*
X640000Y1680000D03*
X660000D03*
X680000D03*
Y1720000D03*
X640000Y1700000D03*
X660000D03*
Y1720000D03*
X640000D03*
Y1660000D03*
X660000D03*
X680000Y1780000D03*
X660000D03*
X640000D03*
X680000Y1760000D03*
X660000D03*
X640000D03*
X680000Y1740000D03*
X660000D03*
X640000D03*
X680000Y1820000D03*
X660000D03*
X680000Y1800000D03*
X660000D03*
X640000D03*
X680000Y1860000D03*
X660000Y1840000D03*
X640000D03*
Y1860000D03*
X660000D03*
X680000Y1880000D03*
Y1900000D03*
Y1920000D03*
X660000Y1880000D03*
X640000D03*
X660000Y1900000D03*
X640000D03*
X660000Y1920000D03*
X640000D03*
Y1940000D03*
X660000D03*
X680000Y1960000D03*
X660000D03*
X640000D03*
X632559Y1986626D03*
X652559D03*
X672559D03*
X660000Y1980000D03*
X640000D03*
X680000D03*
X692559Y1986626D03*
X700000Y20000D03*
X740000Y40000D03*
X750018Y5500D03*
X730018D03*
X710018D03*
X740000Y20000D03*
X720000D03*
X760000Y40000D03*
Y20000D03*
X700000Y120000D03*
X720000D03*
X740000D03*
X700000Y80000D03*
Y60000D03*
Y100000D03*
X720000D03*
Y60000D03*
X740000D03*
Y80000D03*
X720000D03*
X740000Y100000D03*
X760000Y120000D03*
Y100000D03*
Y80000D03*
Y60000D03*
X700000Y180000D03*
X740000D03*
X720000D03*
Y140000D03*
Y160000D03*
X760000D03*
X740000D03*
X700000D03*
Y140000D03*
X740000D03*
X760000D03*
Y180000D03*
X700000Y260000D03*
Y240000D03*
Y220000D03*
Y200000D03*
X720000Y260000D03*
Y240000D03*
Y220000D03*
Y200000D03*
X740000Y260000D03*
Y200000D03*
Y220000D03*
Y240000D03*
X760000Y260000D03*
Y200000D03*
Y220000D03*
Y240000D03*
Y320000D03*
X700000D03*
Y300000D03*
Y280000D03*
X720000Y320000D03*
Y300000D03*
Y280000D03*
X740000D03*
Y300000D03*
X760000Y280000D03*
X740000Y400000D03*
X720000D03*
X700000D03*
X740000Y380000D03*
X720000D03*
X760000Y400000D03*
Y360000D03*
Y380000D03*
Y460000D03*
Y480000D03*
X740000D03*
X720000D03*
X700000D03*
Y420000D03*
X720000D03*
X740000D03*
Y440000D03*
X720000D03*
X700000D03*
Y460000D03*
X720000D03*
X740000D03*
X760000Y420000D03*
Y440000D03*
X720000Y520000D03*
X700000D03*
X740000Y500000D03*
X720000D03*
X740000Y520000D03*
X700000Y500000D03*
Y540000D03*
X740000D03*
X720000D03*
X760000D03*
Y520000D03*
Y500000D03*
Y560000D03*
X720000D03*
X740000D03*
X700000D03*
X740000Y600000D03*
Y580000D03*
X720000D03*
X740000Y620000D03*
X720000D03*
X700000Y580000D03*
Y600000D03*
X720000D03*
X760000Y620000D03*
Y600000D03*
Y580000D03*
Y680000D03*
Y640000D03*
X740000D03*
Y680000D03*
X720000D03*
X700000D03*
Y660000D03*
X720000D03*
X740000D03*
X700000Y640000D03*
X720000D03*
X700000Y720000D03*
X720000D03*
X740000D03*
Y760000D03*
X720000D03*
X700000D03*
Y740000D03*
X720000D03*
X740000D03*
X760000Y760000D03*
Y740000D03*
Y720000D03*
X740000Y840000D03*
X700000D03*
X720000D03*
X740000Y800000D03*
X720000D03*
X700000D03*
Y820000D03*
X720000D03*
X740000D03*
X700000Y780000D03*
X720000D03*
X740000D03*
X760000Y840000D03*
Y800000D03*
Y820000D03*
Y780000D03*
X740000Y920000D03*
X700000D03*
X720000D03*
X740000Y900000D03*
Y880000D03*
Y860000D03*
X700000Y900000D03*
X720000D03*
X700000Y880000D03*
X720000D03*
X700000Y860000D03*
X720000D03*
X760000Y920000D03*
Y900000D03*
Y880000D03*
Y860000D03*
X700000Y980000D03*
X720000D03*
X740000D03*
X700000Y960000D03*
X720000D03*
X740000D03*
X760000Y980000D03*
Y960000D03*
X740000Y1040000D03*
X720000D03*
X700000D03*
X760000D03*
X700000Y1120000D03*
Y1100000D03*
X720000Y1120000D03*
X740000D03*
Y1080000D03*
X700000D03*
X760000Y1120000D03*
X740000Y1160000D03*
X720000D03*
X700000D03*
Y1200000D03*
X720000D03*
X740000D03*
X760000Y1160000D03*
Y1200000D03*
X700000Y1240000D03*
X740000Y1260000D03*
X720000D03*
X700000D03*
X740000Y1280000D03*
X720000D03*
X700000D03*
Y1220000D03*
X720000D03*
X740000D03*
Y1240000D03*
X720000D03*
X760000D03*
Y1260000D03*
Y1280000D03*
Y1220000D03*
X740000Y1340000D03*
X720000D03*
X700000D03*
X740000Y1300000D03*
X720000D03*
X700000D03*
Y1320000D03*
X740000D03*
X720000D03*
X760000Y1340000D03*
Y1300000D03*
Y1320000D03*
X740000Y1420000D03*
X720000D03*
X740000Y1380000D03*
Y1360000D03*
X720000Y1380000D03*
Y1360000D03*
X700000Y1380000D03*
Y1360000D03*
X760000Y1420000D03*
Y1380000D03*
Y1360000D03*
X700000Y1500000D03*
X740000Y1440000D03*
X720000D03*
X700000D03*
X740000Y1480000D03*
X720000D03*
X700000D03*
X760000Y1440000D03*
Y1480000D03*
X740000Y1520000D03*
X720000D03*
X760000D03*
X700000Y1680000D03*
X740000Y1700000D03*
X720000D03*
Y1720000D03*
X740000D03*
Y1680000D03*
X720000D03*
X760000Y1720000D03*
X753500Y1662000D03*
Y1666500D03*
X759000Y1662000D03*
Y1666500D03*
X765500Y1662000D03*
Y1666500D03*
X700000Y1780000D03*
Y1760000D03*
Y1740000D03*
X720000Y1780000D03*
X740000Y1740000D03*
X760000Y1780000D03*
Y1740000D03*
X758000Y1756000D03*
X759700Y1817500D03*
X700000Y1820000D03*
Y1800000D03*
Y1860000D03*
X720000D03*
X740000D03*
X720000Y1800000D03*
X740000D03*
Y1820000D03*
X720000D03*
X759700Y1837500D03*
X720000Y1880000D03*
X740000Y1900000D03*
Y1880000D03*
X700000D03*
Y1900000D03*
Y1920000D03*
X720000Y1940000D03*
Y1900000D03*
Y1920000D03*
X700000Y1940000D03*
X760000Y1880000D03*
Y1940000D03*
X728700Y1933100D03*
X720000Y1960000D03*
X700000D03*
X720000Y1980000D03*
X700000D03*
X712559Y1986626D03*
X732559D03*
X740000Y1960000D03*
Y1980000D03*
X752559Y1986626D03*
X759900Y1959200D03*
X760000Y1980000D03*
X755995Y1968282D03*
X800000Y40000D03*
X820000D03*
X840000D03*
X780000D03*
X810018Y5500D03*
X790018D03*
X770018D03*
X780000Y20000D03*
X800000D03*
X820000D03*
X830018Y5500D03*
X840000Y20000D03*
X800000Y120000D03*
X820000D03*
X840000D03*
X800000Y100000D03*
X820000D03*
X840000D03*
X800000Y80000D03*
X820000D03*
X840000D03*
X800000Y60000D03*
X820000D03*
X840000D03*
X780000Y120000D03*
Y60000D03*
Y80000D03*
Y100000D03*
Y160000D03*
X840000Y140000D03*
X820000D03*
X800000D03*
X816000Y187000D03*
X780000Y140000D03*
Y180000D03*
X828500Y171000D03*
X840000Y174250D03*
X820500Y171000D03*
X792343Y193599D03*
X832500Y171000D03*
X824500D03*
X816500D03*
X820000Y260000D03*
X780000Y200000D03*
Y220000D03*
Y240000D03*
X800000Y220000D03*
Y240000D03*
X820000Y220000D03*
X840000Y240000D03*
X828000Y203000D03*
X792343Y197402D03*
X780000Y300000D03*
X800000Y280000D03*
Y340000D03*
X780000D03*
Y380000D03*
Y360000D03*
Y400000D03*
X820000D03*
X800000D03*
Y380000D03*
Y360000D03*
X840000Y400000D03*
X824335Y365915D03*
X815375Y362750D03*
X813350Y369250D03*
X780000Y440000D03*
Y420000D03*
Y460000D03*
X800000Y480000D03*
X820000Y420000D03*
Y440000D03*
Y460000D03*
X800000D03*
Y440000D03*
Y420000D03*
X820000Y480000D03*
X780000D03*
X840000D03*
Y420000D03*
Y440000D03*
Y460000D03*
X780000Y540000D03*
X800000D03*
X820000D03*
X780000Y500000D03*
X820000D03*
Y520000D03*
X800000Y500000D03*
Y520000D03*
X780000D03*
X840000Y500000D03*
Y520000D03*
Y540000D03*
X780000Y580000D03*
Y560000D03*
X800000Y600000D03*
Y580000D03*
Y560000D03*
X780000Y620000D03*
X800000D03*
X820000D03*
X780000Y600000D03*
X820000Y580000D03*
Y560000D03*
Y600000D03*
X840000Y620000D03*
Y580000D03*
Y560000D03*
Y600000D03*
X820000Y700000D03*
X780000D03*
X778400Y659800D03*
X800000Y640000D03*
X780000D03*
X820000Y660000D03*
X798400Y659800D03*
X840000Y640000D03*
Y680000D03*
Y660000D03*
Y700000D03*
X782500Y648000D03*
X820000Y720000D03*
X800000Y760000D03*
X780000D03*
Y740000D03*
X800000D03*
Y720000D03*
X780000D03*
X840000D03*
X824335Y771415D03*
X815375Y768250D03*
X780000Y840000D03*
X800000D03*
X820000D03*
Y820000D03*
X780000Y800000D03*
Y780000D03*
X800000D03*
X840000Y840000D03*
Y800000D03*
Y820000D03*
X780000Y920000D03*
X800000D03*
X820000D03*
X780000Y900000D03*
X800000D03*
X820000D03*
X780000Y880000D03*
X800000D03*
X820000D03*
X780000Y860000D03*
X800000D03*
X820000D03*
X840000Y920000D03*
Y860000D03*
Y880000D03*
Y900000D03*
X780000Y980000D03*
X800000D03*
X820000D03*
X780000Y960000D03*
X800000D03*
X820000D03*
X840000D03*
Y980000D03*
X800000Y1060000D03*
X820000D03*
X780000D03*
X820000Y1040000D03*
X840000Y1060000D03*
Y1040000D03*
X780000Y1120000D03*
X800000D03*
Y1080000D03*
Y1100000D03*
X820000Y1120000D03*
X800000Y1200000D03*
X820000D03*
X780000Y1160000D03*
X800000D03*
X780000Y1200000D03*
X840000D03*
X824335Y1176915D03*
X815375Y1173750D03*
X820000Y1220000D03*
Y1240000D03*
X800000D03*
X780000D03*
X820000Y1260000D03*
X800000D03*
X780000D03*
X820000Y1280000D03*
X800000D03*
X780000D03*
Y1220000D03*
X800000D03*
X840000Y1280000D03*
Y1220000D03*
Y1240000D03*
Y1260000D03*
X820000Y1340000D03*
X800000D03*
X780000D03*
X820000Y1300000D03*
X800000D03*
X780000D03*
Y1320000D03*
X820000D03*
X800000D03*
X840000Y1340000D03*
Y1300000D03*
Y1320000D03*
X820000Y1420000D03*
X800000D03*
X780000D03*
X820000Y1380000D03*
Y1360000D03*
X800000Y1380000D03*
Y1360000D03*
X780000Y1380000D03*
Y1360000D03*
X840000Y1420000D03*
Y1360000D03*
Y1380000D03*
X820000Y1440000D03*
X800000D03*
X780000D03*
X820000Y1480000D03*
X800000D03*
X780000D03*
X840000Y1440000D03*
Y1480000D03*
X800000Y1560000D03*
X780000Y1520000D03*
X840000Y1640000D03*
Y1600000D03*
X824335Y1582415D03*
X816625Y1579250D03*
X813000Y1585750D03*
X808500Y1621500D03*
X814000D03*
Y1626000D03*
X808500D03*
X814000Y1630500D03*
X808500D03*
X820000Y1680000D03*
X829388Y1695500D03*
X825388D03*
X833388D03*
X837388D03*
X840000Y1680000D03*
Y1660000D03*
X771000Y1662000D03*
Y1666500D03*
X780000Y1780000D03*
X800000D03*
Y1740000D03*
X780000D03*
X795500Y1755000D03*
X825388Y1739500D03*
X829388D03*
X833388D03*
X837388D03*
X837500Y1785000D03*
X829500D03*
X819000D03*
X815000D03*
X816000Y1801000D03*
X780000Y1800000D03*
X800000D03*
X780000Y1840000D03*
X800000Y1820000D03*
X820000D03*
X828000Y1862000D03*
X827500Y1817000D03*
X834750Y1823285D03*
X819000Y1839000D03*
X800000Y1920000D03*
X820000D03*
X780000D03*
X820000Y1980000D03*
X772559Y1986626D03*
X792559D03*
X812559D03*
X769239Y1955776D03*
X780000Y1980000D03*
X800000D03*
X823400Y1973400D03*
X827900D03*
X835900Y1973500D03*
X839400D03*
X832559Y1986626D03*
X840000Y1980000D03*
X799205Y1960532D03*
X774989Y1955708D03*
X780214Y1953257D03*
X860000Y40000D03*
X880000D03*
X890018Y5500D03*
X870018D03*
X850018D03*
X880000Y20000D03*
X860000D03*
X900000Y40000D03*
X910018Y5500D03*
X900000Y20000D03*
X860000Y120000D03*
X880000D03*
X860000Y100000D03*
X880000D03*
X860000Y80000D03*
X880000D03*
X860000Y60000D03*
X880000D03*
X900000Y120000D03*
Y60000D03*
Y100000D03*
Y80000D03*
X860000Y140000D03*
X908493Y136513D03*
X880000Y180000D03*
X869250Y144750D03*
X885993Y134893D03*
X885531Y164804D03*
X896441Y147203D03*
X844000Y190000D03*
X866961Y162539D03*
X896547Y150803D03*
X890469Y164804D03*
X864975Y148875D03*
X863441Y219890D03*
X876441Y262165D03*
Y255866D03*
X863307Y264102D03*
X860000Y260000D03*
X876441Y246417D03*
Y236968D03*
Y230669D03*
Y221220D03*
Y211771D03*
X863441Y213102D03*
X860000Y240000D03*
X899941Y233917D03*
Y218917D03*
Y203917D03*
X908654Y231105D03*
X904838D03*
X872500Y241500D03*
X876500Y251000D03*
X901441Y244842D03*
X908346Y235394D03*
X905146D03*
X872941Y223745D03*
Y228145D03*
X867441Y214896D03*
Y218096D03*
Y265290D03*
X901600Y249800D03*
X863307Y269678D03*
X863441Y288972D03*
X863346Y301768D03*
X860100Y336500D03*
X873600Y332200D03*
X860100Y333000D03*
X876441Y318858D03*
Y309409D03*
Y299960D03*
Y290511D03*
Y281063D03*
Y271614D03*
X863346Y307602D03*
X863441Y282602D03*
X901500Y312500D03*
X899941Y283917D03*
Y278917D03*
X856200Y337300D03*
X844050D03*
X872941Y274138D03*
Y278538D03*
Y293036D03*
Y297436D03*
Y311934D03*
Y316334D03*
X867441Y268490D03*
Y284187D03*
Y287387D03*
Y303085D03*
Y306285D03*
X899941Y308917D03*
X865000Y371000D03*
X868500D03*
X876000D03*
X872500D03*
X879600Y385200D03*
X860000Y400000D03*
X880000D03*
X900000D03*
X899900Y382300D03*
X850966Y370025D03*
X880000Y480000D03*
X860000D03*
X880000Y420000D03*
X860000D03*
X880000Y440000D03*
X860000D03*
X880000Y460000D03*
X860000D03*
X900000Y480000D03*
Y420000D03*
Y440000D03*
Y460000D03*
X907493Y542025D03*
X880000Y500000D03*
X860000D03*
X880000Y520000D03*
X860000D03*
X900000Y500000D03*
Y520000D03*
X872875Y535275D03*
X891250Y537500D03*
X895547Y552715D03*
X857735Y553465D03*
X895547Y556315D03*
X865125Y544000D03*
X863441Y625402D03*
X876441Y626732D03*
Y617283D03*
X863441Y618614D03*
X860000Y580000D03*
Y560000D03*
X880000Y580000D03*
Y600000D03*
X860000D03*
X899941Y624429D03*
Y609429D03*
X900000Y600000D03*
X883781Y564519D03*
X872941Y629257D03*
X867441Y620408D03*
Y623608D03*
X888719Y564519D03*
X863441Y694484D03*
X863287Y669690D03*
X876441Y661378D03*
Y651929D03*
Y642480D03*
Y636181D03*
X863287Y675114D03*
X863441Y688114D03*
X876441Y696023D03*
Y686575D03*
Y677126D03*
Y667677D03*
X899941Y684429D03*
Y639429D03*
X908654Y636613D03*
X904838D03*
X899941Y689429D03*
X868500Y654000D03*
X876500Y648000D03*
X901441Y650354D03*
X908346Y640906D03*
X905146D03*
X872941Y633657D03*
Y679650D03*
Y684050D03*
Y698548D03*
Y702948D03*
X867441Y670802D03*
Y674002D03*
Y689699D03*
Y692899D03*
X901200Y655100D03*
X863397Y713280D03*
X859500Y741800D03*
X876441Y724370D03*
Y714921D03*
Y705472D03*
X863397Y707114D03*
X873400Y738400D03*
X859500Y738300D03*
X901500Y718000D03*
X856100Y743300D03*
X850966Y775525D03*
X846200Y743300D03*
X872941Y717446D03*
Y721846D03*
X867441Y708597D03*
Y711797D03*
X899941Y714429D03*
X860000Y840000D03*
X880000D03*
X864500Y776500D03*
X868000D03*
X872000D03*
X875500D03*
X860000Y800000D03*
X880000D03*
X860000Y820000D03*
X880000D03*
X900000Y840000D03*
Y800000D03*
Y820000D03*
X860000Y920000D03*
X880000D03*
X860000Y860000D03*
X880000D03*
X860000Y880000D03*
X880000D03*
X860000Y900000D03*
X880000D03*
X900000Y920000D03*
Y860000D03*
Y880000D03*
Y900000D03*
X907493Y947537D03*
X860000Y980000D03*
X886517Y945917D03*
X872875Y940925D03*
X883781Y970031D03*
X895547Y958227D03*
X857623Y958977D03*
X895547Y961827D03*
X888719Y970031D03*
X865125Y949600D03*
X863441Y1030914D03*
X876441Y1066890D03*
Y1057441D03*
Y1047992D03*
Y1041693D03*
Y1032244D03*
Y1022795D03*
X863441Y1024126D03*
X880000Y1000000D03*
X860000Y1040000D03*
X899941Y1044941D03*
Y1029941D03*
Y1014941D03*
X908654Y1042129D03*
X904838D03*
X900000Y1000000D03*
Y1040000D03*
Y1020000D03*
X868500Y1059500D03*
X901441Y1055866D03*
X876500Y1053500D03*
X908346Y1046418D03*
X905146D03*
X872941Y1034769D03*
Y1039169D03*
X867441Y1025920D03*
Y1029120D03*
X901300Y1060700D03*
X863346Y1112792D03*
X863441Y1099996D03*
X863308Y1080702D03*
X876441Y1129882D03*
Y1120433D03*
Y1110984D03*
Y1101535D03*
Y1092087D03*
Y1082638D03*
Y1073189D03*
X863308Y1075126D03*
X863441Y1093626D03*
X863346Y1118626D03*
X899941Y1094941D03*
Y1089941D03*
X900000Y1080000D03*
X901500Y1123500D03*
X872941Y1085162D03*
Y1089562D03*
Y1104060D03*
Y1108460D03*
Y1122958D03*
Y1127358D03*
X867441Y1076314D03*
Y1079514D03*
Y1095211D03*
Y1098411D03*
Y1114109D03*
Y1117309D03*
X899941Y1119941D03*
X859500Y1147600D03*
X874200Y1144000D03*
X859500Y1144100D03*
X864000Y1181900D03*
X867500D03*
X872200D03*
X875700D03*
X860000Y1200000D03*
X880000D03*
X900000D03*
X854500Y1148700D03*
X850600Y1181025D03*
X844600Y1148700D03*
X860000Y1280000D03*
X880000D03*
X860000Y1220000D03*
Y1240000D03*
Y1260000D03*
X880000Y1220000D03*
Y1240000D03*
Y1260000D03*
X900000Y1280000D03*
Y1220000D03*
Y1240000D03*
Y1260000D03*
X907493Y1353048D03*
X880000Y1340000D03*
X860000D03*
Y1300000D03*
Y1320000D03*
X880000D03*
Y1300000D03*
X900000Y1320000D03*
Y1300000D03*
X872875Y1346488D03*
X891250Y1348500D03*
X865125Y1346488D03*
X876441Y1428307D03*
X863441Y1429638D03*
X860000Y1420000D03*
Y1380000D03*
X899941Y1420453D03*
X883219Y1373504D03*
X895647Y1363738D03*
X857688Y1364488D03*
X895647Y1367338D03*
X887438Y1373374D03*
X863286Y1480714D03*
X863441Y1436426D03*
X876441Y1478701D03*
Y1472402D03*
Y1462953D03*
Y1453504D03*
Y1447205D03*
Y1437756D03*
X860000Y1440000D03*
X876441Y1497599D03*
Y1488150D03*
X863286Y1486138D03*
X863441Y1499138D03*
X899941Y1450453D03*
Y1435453D03*
X908654Y1447641D03*
X904838D03*
X899941Y1500453D03*
Y1495453D03*
X868500Y1465000D03*
X901441Y1461378D03*
X876500Y1459000D03*
X908346Y1451930D03*
X905146D03*
X872941Y1440281D03*
Y1444681D03*
Y1490674D03*
Y1495074D03*
X867441Y1431432D03*
Y1434632D03*
Y1481826D03*
Y1485026D03*
Y1500723D03*
X901400Y1466100D03*
X863347Y1518304D03*
X863441Y1505508D03*
X859500Y1553200D03*
X876441Y1535394D03*
Y1525945D03*
Y1516496D03*
Y1507047D03*
X863347Y1524138D03*
X873300Y1549100D03*
X859500Y1549700D03*
X901500Y1529000D03*
X855500Y1554300D03*
X845600D03*
X872941Y1509572D03*
Y1513972D03*
Y1528470D03*
Y1532870D03*
X867441Y1503923D03*
Y1519621D03*
Y1522821D03*
X899941Y1525453D03*
X860000Y1640000D03*
Y1580000D03*
X865500Y1589000D03*
X869000D03*
X873000D03*
X876500D03*
X880000Y1599000D03*
X900000Y1600000D03*
X850966Y1586525D03*
X891500Y1712000D03*
X895500D03*
Y1708000D03*
X841388Y1695500D03*
X873962Y1672000D03*
Y1676500D03*
Y1681500D03*
Y1685500D03*
X860000Y1660000D03*
X906000Y1713500D03*
X885750Y1701500D03*
X891500Y1708000D03*
X891000Y1720000D03*
X896500Y1681000D03*
X859500Y1696000D03*
X886600Y1756100D03*
X872875Y1751600D03*
X906500Y1734100D03*
X907493Y1758560D03*
X910500Y1734600D03*
X895547Y1769250D03*
X883781Y1781054D03*
X895547Y1772850D03*
X888719Y1781054D03*
X865125Y1751800D03*
X902500Y1734000D03*
X910500Y1724700D03*
X863441Y1841938D03*
X876441Y1859016D03*
Y1852717D03*
X860000Y1860000D03*
X876441Y1843268D03*
Y1833819D03*
X863441Y1835150D03*
X899941Y1855965D03*
X908654Y1853153D03*
X904838D03*
X899941Y1840965D03*
Y1825965D03*
X876000Y1864000D03*
X901441Y1866890D03*
X908346Y1857442D03*
X905146D03*
X872941Y1845793D03*
Y1850193D03*
X867441Y1836944D03*
Y1840144D03*
X863346Y1923816D03*
X863441Y1911020D03*
X863287Y1886226D03*
X876441Y1912559D03*
Y1903111D03*
Y1893662D03*
Y1884213D03*
Y1877914D03*
Y1868465D03*
X863287Y1891650D03*
X863441Y1904650D03*
X860000Y1880000D03*
X876441Y1931457D03*
Y1922008D03*
X863346Y1929650D03*
X901500Y1934500D03*
X899941Y1905965D03*
Y1900965D03*
X867500Y1870000D03*
X872941Y1896186D03*
Y1900586D03*
Y1915084D03*
Y1919484D03*
Y1933982D03*
Y1938382D03*
X867441Y1887338D03*
Y1890538D03*
Y1906235D03*
Y1909435D03*
Y1925133D03*
Y1928333D03*
X899941Y1930965D03*
X901200Y1871600D03*
X876441Y1940906D03*
X843500Y1973500D03*
X847000D03*
X852559Y1986626D03*
X872559D03*
X896546Y1986566D03*
X860000Y1980000D03*
X912559Y1986626D03*
X844800Y1949700D03*
X858800Y1951300D03*
X879500Y1970000D03*
X880000Y1955500D03*
X862000Y1969900D03*
Y1960500D03*
X844700Y1945200D03*
X960000Y40000D03*
X940000D03*
X920000D03*
X950018Y5500D03*
X930018D03*
X920000Y20000D03*
X940000D03*
X960000D03*
X980000Y40000D03*
X970018Y5500D03*
X980000Y20000D03*
X960000Y120000D03*
X940000D03*
X920000D03*
Y60000D03*
X940000D03*
X960000D03*
X920000Y100000D03*
X940000D03*
X960000D03*
Y80000D03*
X940000D03*
X920000D03*
X980000Y120000D03*
Y60000D03*
Y100000D03*
Y80000D03*
X960000Y140000D03*
X940000D03*
X960000Y160000D03*
X940000D03*
Y180000D03*
X960000D03*
X980000D03*
X926347Y160000D03*
Y164453D03*
X921400Y235002D03*
Y245200D03*
X940000Y200000D03*
X960000D03*
Y220000D03*
X940000D03*
Y240000D03*
X960000D03*
Y260000D03*
X940000D03*
X980000Y240000D03*
Y260000D03*
Y200000D03*
Y220000D03*
X918846Y238501D03*
Y241701D03*
X940000Y280000D03*
X920000D03*
X960000D03*
X920000Y300000D03*
X940000D03*
X960000D03*
X920000Y320000D03*
X940000D03*
X960000D03*
X980000Y280000D03*
Y300000D03*
Y320000D03*
X960000Y400000D03*
X940000D03*
X920000D03*
X960000Y340000D03*
X940000D03*
X920000D03*
Y360000D03*
X940000D03*
X960000D03*
Y380000D03*
X940000D03*
X920000D03*
X980000Y400000D03*
Y340000D03*
Y360000D03*
Y380000D03*
X920000Y480000D03*
X940000D03*
X960000D03*
X920000Y420000D03*
X940000D03*
X960000D03*
X920000Y440000D03*
X940000D03*
X960000D03*
X920000Y460000D03*
X940000D03*
X960000D03*
X980000Y480000D03*
Y420000D03*
Y440000D03*
Y460000D03*
X920000Y500000D03*
X940000D03*
X960000D03*
X920000Y520000D03*
X940000D03*
X960000D03*
Y540000D03*
X980000Y500000D03*
Y520000D03*
Y540000D03*
X940000Y620000D03*
X960000D03*
Y560000D03*
Y580000D03*
Y600000D03*
X940000Y580000D03*
Y600000D03*
X920000Y580000D03*
Y600000D03*
X980000Y620000D03*
Y560000D03*
Y580000D03*
Y600000D03*
X926365Y569965D03*
Y565500D03*
X919000Y639715D03*
X920000Y700000D03*
X919000Y651511D03*
X940000Y640000D03*
X960000D03*
X920000Y680000D03*
X940000D03*
X960000D03*
Y660000D03*
X940000D03*
X920000D03*
X940000Y700000D03*
X960000D03*
X980000Y640000D03*
Y660000D03*
Y700000D03*
X918846Y644013D03*
Y647213D03*
X940000Y760000D03*
X960000D03*
X920000D03*
Y740000D03*
Y720000D03*
X940000D03*
X960000D03*
X940000Y740000D03*
X960000D03*
X980000Y760000D03*
Y720000D03*
Y740000D03*
X940000Y840000D03*
X960000D03*
X920000D03*
X940000Y780000D03*
X960000D03*
X940000Y800000D03*
X960000D03*
X940000Y820000D03*
X960000D03*
X920000Y800000D03*
Y820000D03*
Y780000D03*
X980000Y840000D03*
Y780000D03*
Y800000D03*
Y820000D03*
X940000Y920000D03*
X960000D03*
X920000D03*
X940000Y860000D03*
X960000D03*
X940000Y880000D03*
X960000D03*
X940000Y900000D03*
X960000D03*
X920000Y860000D03*
Y880000D03*
Y900000D03*
X980000Y920000D03*
Y860000D03*
Y880000D03*
Y900000D03*
X960000Y980000D03*
Y940000D03*
X940000D03*
X960000Y960000D03*
X980000Y980000D03*
Y940000D03*
Y960000D03*
X926477Y971000D03*
Y975477D03*
X922900Y1048050D03*
Y1054200D03*
X920000Y1060000D03*
X940000D03*
X960000D03*
Y1000000D03*
X940000D03*
X920000D03*
Y1020000D03*
X940000D03*
X960000D03*
Y1040000D03*
X940000D03*
X920000D03*
X980000Y1000000D03*
Y1020000D03*
Y1040000D03*
X918846Y1049525D03*
Y1052725D03*
X940000Y1140000D03*
X960000D03*
X920000Y1080000D03*
X940000D03*
X960000D03*
Y1100000D03*
X940000D03*
X920000Y1120000D03*
X940000D03*
X960000D03*
X920000Y1140000D03*
X980000D03*
Y1100000D03*
X979962Y1075211D03*
X980000Y1120000D03*
X923000Y1160200D03*
X940000Y1160000D03*
X960000D03*
Y1180000D03*
X940000D03*
X923000Y1180200D03*
X960000Y1200000D03*
X940000D03*
X920000D03*
X980000Y1160000D03*
Y1180000D03*
Y1200000D03*
X960000Y1280000D03*
X940000D03*
X920000D03*
X960000Y1220000D03*
X940000D03*
X960000Y1240000D03*
X940000D03*
X960000Y1260000D03*
X940000D03*
X920000Y1220000D03*
Y1240000D03*
Y1260000D03*
X980000Y1220000D03*
Y1240000D03*
Y1260000D03*
Y1280000D03*
X960000Y1340000D03*
X940000D03*
X920000D03*
X960000Y1300000D03*
X940000D03*
X960000Y1320000D03*
X940000D03*
X920000Y1300000D03*
Y1320000D03*
X980000Y1340000D03*
Y1300000D03*
Y1320000D03*
X981700Y1409000D03*
X954300Y1412600D03*
X960000Y1360000D03*
Y1380000D03*
Y1400000D03*
X940000D03*
X920000D03*
X963500Y1409000D03*
X973000D03*
X968000D03*
X977500D03*
X980000Y1360000D03*
Y1380000D03*
Y1400000D03*
X926300Y1380988D03*
Y1376500D03*
X919000Y1450734D03*
Y1462540D03*
X920000Y1480000D03*
Y1440000D03*
X918846Y1455037D03*
Y1458237D03*
X920000Y1520000D03*
Y1540000D03*
X923800Y1559300D03*
X923500Y1579800D03*
X920000Y1600000D03*
X959000Y1631000D03*
X943500Y1646989D03*
X973000Y1641500D03*
X931000Y1659000D03*
X960000Y1700000D03*
Y1720000D03*
X933000Y1704000D03*
X951500Y1658000D03*
X952000Y1678000D03*
X980000Y1700000D03*
Y1720000D03*
X963500Y1675000D03*
Y1657000D03*
X959000D03*
Y1675000D03*
X926500Y1660000D03*
X941000Y1653000D03*
X934825Y1682285D03*
X947000Y1654500D03*
X915250Y1687500D03*
X919250Y1711500D03*
X960000Y1740000D03*
Y1760000D03*
X940000D03*
X933000Y1736500D03*
X925500Y1738000D03*
X960000Y1780000D03*
X980000D03*
Y1740000D03*
Y1760000D03*
X916500Y1729500D03*
X926400Y1782000D03*
Y1786500D03*
X921900Y1722400D03*
X919000Y1856251D03*
X960000Y1860000D03*
X940000D03*
X960000Y1800000D03*
X940000D03*
X920000D03*
X940000Y1820000D03*
X960000D03*
X940000Y1840000D03*
X960000D03*
X920000D03*
X980000Y1860000D03*
Y1800000D03*
Y1820000D03*
Y1840000D03*
X918846Y1860549D03*
Y1863749D03*
X920000Y1920000D03*
X940000D03*
X960000D03*
Y1940000D03*
X940000D03*
X920000D03*
X919000Y1868047D03*
X960000Y1880000D03*
X940000D03*
X920000D03*
X960000Y1900000D03*
X940000D03*
X920000D03*
X980000Y1920000D03*
Y1940000D03*
X980018Y1897856D03*
X932559Y1986626D03*
X952559D03*
X960000Y1960000D03*
X940000D03*
X920000D03*
Y1980000D03*
X940000D03*
X960000D03*
X972559Y1986626D03*
X980000Y1960000D03*
Y1980000D03*
X1031902Y43616D03*
X1020000Y40000D03*
X1000000D03*
X1031902Y23616D03*
X1030018Y5500D03*
X1010018D03*
X990018D03*
X1000000Y20000D03*
X1020000D03*
Y120000D03*
X1000000D03*
X1031902Y63616D03*
Y103616D03*
Y83616D03*
X1000000Y60000D03*
X1020000D03*
X1000000Y100000D03*
X1020000D03*
Y80000D03*
X1000000D03*
X1031902Y143616D03*
Y123616D03*
Y163616D03*
X1020000Y140000D03*
Y160000D03*
Y180000D03*
X1031902Y183616D03*
X1000000Y240000D03*
X1020000D03*
X1031902Y263616D03*
X1020000Y260000D03*
X1000000D03*
X1031902Y223616D03*
Y203616D03*
Y243616D03*
X1000000Y200000D03*
X1020000D03*
Y220000D03*
X1000000D03*
X1031902Y303616D03*
Y283616D03*
Y323616D03*
X1000000Y280000D03*
X1020000D03*
X1000000Y300000D03*
X1020000D03*
X1000000Y320000D03*
X1020000D03*
X1031902Y403616D03*
X1020000Y400000D03*
X1000000D03*
X1031902Y383616D03*
Y363616D03*
Y343616D03*
X1020000Y340000D03*
X1000000D03*
Y360000D03*
X1020000D03*
Y380000D03*
X1000000D03*
X1031902Y483616D03*
X1000000Y480000D03*
X1020000D03*
X1031902Y443616D03*
Y423616D03*
Y463616D03*
X1000000Y420000D03*
X1020000D03*
X1000000Y440000D03*
X1020000D03*
X1000000Y460000D03*
X1020000D03*
X1031902Y523616D03*
Y503616D03*
Y543616D03*
X1000000Y500000D03*
X1020000D03*
X1000000Y520000D03*
X1020000D03*
X1000000Y540000D03*
X1020000D03*
X1031902Y623616D03*
X1000000Y620000D03*
X1020000D03*
X1031902Y603616D03*
Y583616D03*
Y563616D03*
X1020000Y560000D03*
X1000000D03*
X1020000Y580000D03*
X1000000D03*
X1020000Y600000D03*
X1000000D03*
X1031902Y683616D03*
Y663616D03*
Y643616D03*
X1000000Y640000D03*
X1020000D03*
Y660000D03*
Y680000D03*
Y700000D03*
X1000000Y740000D03*
X1020000D03*
X1000000Y760000D03*
X1020000D03*
X1031902Y763616D03*
Y743616D03*
Y723616D03*
Y703616D03*
X1000000Y720000D03*
X1020000D03*
X1031902Y843616D03*
X1000000Y840000D03*
X1020000D03*
X1031902Y823616D03*
Y803616D03*
Y783616D03*
X1000000Y780000D03*
X1020000D03*
X1000000Y800000D03*
X1020000D03*
X1000000Y820000D03*
X1020000D03*
X1000000Y920000D03*
X1020000D03*
X1031902Y903616D03*
Y883616D03*
Y863616D03*
X1000000Y860000D03*
X1020000D03*
X1000000Y880000D03*
X1020000D03*
X1000000Y900000D03*
X1020000D03*
X1031902Y983616D03*
X1000000Y980000D03*
X1020000D03*
X1031902Y963616D03*
Y943616D03*
Y923616D03*
X1020000Y940000D03*
X1000000D03*
Y960000D03*
X1020000D03*
X1031902Y1063616D03*
X1020000Y1060000D03*
X1031902Y1043616D03*
Y1023616D03*
Y1003616D03*
X1020000Y1000000D03*
X1000000D03*
Y1020000D03*
X1020000D03*
Y1040000D03*
X1000000D03*
X1031902Y1123616D03*
X1000000Y1140000D03*
X1020000D03*
X1031902Y1103616D03*
Y1083616D03*
X1020000Y1080000D03*
Y1100000D03*
X999922Y1102598D03*
X1000000Y1120000D03*
X1020000D03*
X1031902Y1143616D03*
Y1183616D03*
Y1163616D03*
X1000000Y1160000D03*
X1020000D03*
Y1180000D03*
X1000000D03*
X1031902Y1203616D03*
X1020000Y1200000D03*
X1000000D03*
Y1220000D03*
X1020000Y1240000D03*
X1000000D03*
X1020000Y1260000D03*
X1000000D03*
X1031902Y1283616D03*
X1020000Y1280000D03*
X1000000D03*
X1031902Y1263616D03*
Y1243616D03*
Y1223616D03*
X1020000Y1220000D03*
X1031902Y1343616D03*
X1020000Y1340000D03*
X1000000D03*
X1031902Y1323616D03*
Y1303616D03*
X1020000Y1300000D03*
X1000000D03*
X1020000Y1320000D03*
X1000000D03*
X986200Y1409000D03*
X994600Y1414100D03*
X990300Y1412500D03*
X1031902Y1363616D03*
Y1383616D03*
X1020000Y1360000D03*
X1000000D03*
Y1380000D03*
X1020000D03*
Y1400000D03*
X1000000D03*
X994898Y1646102D03*
X992500Y1636000D03*
X991602Y1622500D03*
X1000000Y1700000D03*
X1020000Y1720000D03*
X1000000D03*
X995102Y1676102D03*
X995000Y1656102D03*
Y1666102D03*
X1031902Y1785969D03*
X1000000Y1780000D03*
X1020000D03*
X1031902Y1745969D03*
Y1725969D03*
Y1765969D03*
X1000000Y1740000D03*
X1020000D03*
Y1760000D03*
X1000000D03*
X1031902Y1865969D03*
Y1845969D03*
X1020000Y1860000D03*
X1000000D03*
X1031902Y1805969D03*
Y1825969D03*
X1020000Y1800000D03*
X1000000D03*
Y1820000D03*
X1020000D03*
X1000000Y1840000D03*
X1020000D03*
X1031902Y1925969D03*
X999469Y1923465D03*
X1020000Y1920000D03*
Y1940000D03*
X1000000D03*
X1031902Y1885969D03*
Y1905969D03*
X1020000Y1880000D03*
Y1900000D03*
X1031902Y1965969D03*
Y1945969D03*
X992559Y1986626D03*
X1012559D03*
X1031902Y1985969D03*
X1020000Y1960000D03*
X1000000D03*
Y1980000D03*
X1020000D03*
G54D15*
X25000Y988000D03*
X27825Y995000D03*
X78675Y380704D03*
X47500Y660500D03*
X45000Y1057000D03*
X77607Y1565391D03*
X183344Y808200D03*
X126221Y861250D03*
Y853750D03*
X163170Y1210999D03*
X117387Y1536250D03*
Y1543750D03*
X122844Y1672400D03*
X130344D03*
X213244Y23725D03*
X243156Y382060D03*
X235656D03*
X228156Y438500D03*
X220656D03*
X206700Y575000D03*
X190844Y808200D03*
X242700Y1266656D03*
Y1259156D03*
X232344Y1740000D03*
X239844D03*
X284000Y541344D03*
Y548844D03*
X317156Y1193440D03*
X324656D03*
X276344Y1183060D03*
X268844D03*
X401500Y395500D03*
X393500Y422000D03*
X401500Y830000D03*
X393500Y852000D03*
X402000Y1196500D03*
X396637Y1176000D03*
X358156Y1411000D03*
X350656D03*
X402000Y1695000D03*
X379500Y1673750D03*
X427500Y297156D03*
Y304656D03*
X412500Y1130750D03*
Y1138250D03*
X438656Y1669000D03*
X431156D03*
X458156Y1743000D03*
X450656D03*
X512656Y623500D03*
X520156D03*
X555000Y524344D03*
Y531844D03*
X807756Y377775D03*
X808256Y783275D03*
X807756Y1188775D03*
Y1594275D03*
X979500Y1669750D03*
Y1662250D03*
G54D17*
X38800Y1810100D03*
X22100Y1802800D03*
X38317Y1804491D03*
X34900Y1807200D03*
X35100Y1813000D03*
X26500Y1805200D03*
X26600Y1810600D03*
X26300Y1815000D03*
X30800Y1805300D03*
Y1810500D03*
X17500Y1801900D03*
X22000Y1814100D03*
Y1809100D03*
X17500Y1806900D03*
Y1811900D03*
Y1816500D03*
X71200Y36900D03*
X136100Y41200D03*
X965000Y1525000D03*
X955000D03*
X945000D03*
Y1516000D03*
X955000D03*
X965000D03*
X935000Y1555000D03*
X945000D03*
X955000D03*
X965000D03*
X935000Y1575000D03*
Y1565000D03*
X945000Y1575000D03*
X955000D03*
X965000D03*
Y1565000D03*
X955000D03*
X945000D03*
X935000Y1545000D03*
Y1535000D03*
Y1525000D03*
Y1516000D03*
X965000Y1545000D03*
X955000D03*
X945000D03*
Y1535000D03*
X955000D03*
X965000D03*
X975000Y1565000D03*
Y1575000D03*
Y1525000D03*
Y1535000D03*
Y1545000D03*
Y1555000D03*
X965000Y1605000D03*
X935000Y1595000D03*
Y1585000D03*
X945000Y1595000D03*
X955000D03*
X965000D03*
Y1585000D03*
X955000D03*
X945000D03*
X975000Y1595000D03*
Y1605000D03*
Y1585000D03*
G54D13*
X23426Y281496D03*
X24764Y286496D03*
X28426Y290197D03*
X38465D03*
X42166Y286496D03*
X11615Y1922835D03*
X12953Y1927835D03*
X16615Y1931536D03*
X26654D03*
X30355Y1927835D03*
X31693Y1922835D03*
X43504Y281496D03*
X123819Y17717D03*
X125157Y22717D03*
X128819Y26418D03*
X138858D03*
X142559Y22717D03*
X143897Y17717D03*
X265552Y279528D03*
X266890Y284528D03*
X270552Y288229D03*
X280591D03*
X284292Y284528D03*
X285630Y279528D03*
X265552Y685030D03*
X266890Y690030D03*
X270552Y693731D03*
X280591D03*
X284292Y690030D03*
X285630Y685030D03*
X265552Y1088573D03*
X266890Y1093573D03*
X270552Y1097274D03*
X280591D03*
X284292Y1093573D03*
X285630Y1088573D03*
X265552Y1903534D03*
X266890Y1908534D03*
X270552Y1912235D03*
X280591D03*
X284292Y1908534D03*
X285630Y1903534D03*
X987992Y163376D03*
Y686998D03*
Y1082667D03*
Y1903534D03*
X989330Y168376D03*
X992992Y172077D03*
X1003031D03*
X1006732Y168376D03*
X1008070Y163376D03*
X989330Y691998D03*
X992992Y695699D03*
X1003031D03*
X1006732Y691998D03*
X1008070Y686998D03*
X989330Y1087667D03*
X992992Y1091368D03*
X1003031D03*
X1006732Y1087667D03*
X1008070Y1082667D03*
X989330Y1908534D03*
X992992Y1912235D03*
X1003031D03*
X1006732Y1908534D03*
X1008070Y1903534D03*
G54D22*
X57800Y1961800D03*
X296000Y612000D03*
X292000D03*
X316000D03*
X308000D03*
X304000D03*
X317500Y559000D03*
X332500Y593000D03*
Y601000D03*
X898500Y1734000D03*
G54D18*
X7600Y1855000D03*
X17500Y1827500D03*
X22600Y1825200D03*
X17500Y1832500D03*
X22500Y1830000D03*
X17500Y1837500D03*
X22500Y1835000D03*
X17500Y1842500D03*
X22500Y1840000D03*
X17500Y1847500D03*
X22500Y1845000D03*
X17500Y1852500D03*
X22500Y1850000D03*
X17500Y1857500D03*
X22500Y1855000D03*
Y1865000D03*
X17500Y1867500D03*
X22500Y1860000D03*
X12500Y1845000D03*
Y1850000D03*
Y1855000D03*
Y1840000D03*
X17500Y1872500D03*
X22500Y1870000D03*
X12500D03*
X99300Y201000D03*
X89400Y603250D03*
X93000Y1005700D03*
X96250Y1414400D03*
X100300Y1820800D03*
X177300Y39000D03*
X180800D03*
X184300D03*
X180800Y35500D03*
X177300D03*
X184300D03*
X134000Y409500D03*
X137500D03*
X130500D03*
X127000D03*
Y413000D03*
X130500D03*
X134000D03*
X137500D03*
X127000Y818500D03*
X130500D03*
X134000D03*
X137500D03*
X134000Y815000D03*
X137500D03*
X130500D03*
X127000D03*
Y1224000D03*
X130500Y1220500D03*
Y1224000D03*
X134000D03*
X137500D03*
X134000Y1220500D03*
X137500D03*
X127000D03*
X126800Y1630100D03*
X130300D03*
X133800D03*
X126800Y1626600D03*
X130300D03*
X137300Y1630100D03*
Y1626600D03*
X133800D03*
X187800Y39000D03*
Y35500D03*
X198800Y158000D03*
X195250Y561300D03*
X198900Y969500D03*
X193400Y1373000D03*
X197900Y1781500D03*
X293000Y385000D03*
X294500Y408000D03*
X303200Y422600D03*
X320100Y587200D03*
X293500Y738000D03*
X292000Y837000D03*
X295200Y903000D03*
X305200D03*
Y913000D03*
X295200D03*
X303500Y853100D03*
X292500Y965500D03*
X294000Y1111500D03*
X295000Y1245000D03*
X294500Y1254000D03*
X302500Y1224000D03*
X328000Y1381500D03*
Y1374000D03*
X327500Y1368500D03*
X363750Y54250D03*
X369000Y294000D03*
X401500Y410250D03*
X351729Y455810D03*
X379258Y455892D03*
X387249Y455882D03*
X343729Y455810D03*
X336000Y570580D03*
Y578600D03*
X351792Y885835D03*
X379270Y885897D03*
X387292D03*
X343770D03*
X351750Y1257380D03*
X379270D03*
X387292Y1257360D03*
X343760Y1257381D03*
X405500Y277500D03*
X405000Y289000D03*
X410550Y420500D03*
X404000Y840500D03*
X410550Y850500D03*
X405500Y1192000D03*
X408300Y1237500D03*
X547659Y1560537D03*
X542159D03*
Y1566037D03*
X547659D03*
X663000Y535500D03*
X661500Y650500D03*
X662000Y826600D03*
X665000Y937000D03*
X660000Y1053500D03*
X662000Y1183500D03*
X657000Y1331500D03*
X662000Y1459000D03*
X634200Y1561200D03*
Y1565700D03*
X639700Y1561200D03*
Y1565700D03*
X646200Y1561200D03*
Y1565700D03*
X651700Y1561200D03*
Y1565700D03*
X785239Y1960907D03*
X901500Y1681500D03*
X926347Y155500D03*
X926365Y561000D03*
X926477Y966500D03*
X935000Y1425000D03*
X984900Y1430400D03*
X953800Y1424900D03*
X945000Y1425000D03*
X926300Y1372000D03*
X935000Y1455000D03*
Y1475000D03*
Y1445000D03*
Y1465000D03*
Y1435000D03*
X945000Y1475000D03*
X955000D03*
X965000D03*
X945000Y1465000D03*
X955000D03*
X965000D03*
X945000Y1455000D03*
X955000D03*
X965000D03*
X945000Y1445000D03*
X955000D03*
X965000D03*
X945000Y1435000D03*
X955000D03*
X965000D03*
Y1495000D03*
X955000D03*
X935000Y1485000D03*
Y1495000D03*
X945000D03*
Y1485000D03*
X955000D03*
X965000D03*
X975000Y1495000D03*
Y1485000D03*
Y1475000D03*
Y1465000D03*
Y1455000D03*
Y1445000D03*
Y1435000D03*
X935000Y1505000D03*
X955000D03*
X945000D03*
X965000D03*
X926400Y1777500D03*
X990600Y1427100D03*
X995000Y1425000D03*
X1005000D03*
G54D20*
X82087Y28858D03*
Y178464D03*
Y434370D03*
Y583976D03*
Y839882D03*
Y989488D03*
Y1245394D03*
Y1395000D03*
Y1650906D03*
Y1800512D03*
X162008Y191614D03*
Y341220D03*
Y597126D03*
Y746732D03*
Y1002638D03*
Y1152244D03*
Y1408150D03*
Y1557756D03*
Y1813662D03*
Y1963268D03*
X890354Y191614D03*
Y341220D03*
Y597126D03*
Y746732D03*
Y1002638D03*
Y1152244D03*
Y1408150D03*
Y1557756D03*
Y1813662D03*
Y1963268D03*
G54D10*
X-63741Y15000D03*
X-42339Y1008909D03*
X-63741Y1977126D03*
X25499Y1950499D03*
X1010999Y43999D03*
X1010499Y1950499D03*
X1101142Y15000D03*
Y1977126D03*
G54D14*
X11811Y571426D03*
Y949378D03*
Y1067489D03*
Y1484811D03*
Y1445441D03*
Y1862763D03*
G54D16*
X33469Y1029523D03*
X269690Y1490152D03*
G54D24*
X1023228Y1416024D03*
Y1694212D03*
G36*
G01X43453Y275788D02*
G02X23476I-9988J-8073D01*
G03X24559Y278851I-3790J3063D01*
G01Y281496D01*
G02X42370I8906J0D01*
G01Y278851D01*
G03X43453Y275788I4873J0D01*
G37*
G36*
G01X31642Y1917127D02*
G02X11665I-9989J-8073D01*
G03X12748Y1920190I-3790J3063D01*
G01Y1922835D01*
G02X30559I8906J0D01*
G01Y1920190D01*
G03X31642Y1917127I4873J0D01*
G37*
G36*
G01X143846Y12009D02*
G02X123869I-9988J-8073D01*
G03X124952Y15072I-3790J3063D01*
G01Y17717D01*
G02X142763I8905J0D01*
G01Y15072D01*
G03X143846Y12009I4873J0D01*
G37*
G36*
G01X285579Y273820D02*
G02X265602I-9988J-8073D01*
G03X266685Y276883I-3790J3063D01*
G01Y279528D01*
G02X284496I8906J0D01*
G01Y276883D01*
G03X285579Y273820I4873J0D01*
G37*
G36*
G01Y679322D02*
G02X265602I-9988J-8073D01*
G03X266685Y682385I-3790J3063D01*
G01Y685030D01*
G02X284496I8906J0D01*
G01Y682385D01*
G03X285579Y679322I4873J0D01*
G37*
G36*
G01Y1082865D02*
G02X265602I-9988J-8073D01*
G03X266685Y1085928I-3790J3063D01*
G01Y1088573D01*
G02X284496I8906J0D01*
G01Y1085928D01*
G03X285579Y1082865I4873J0D01*
G37*
G36*
G01Y1897826D02*
G02X265602I-9988J-8073D01*
G03X266685Y1900889I-3790J3063D01*
G01Y1903534D01*
G02X284496I8906J0D01*
G01Y1900889D01*
G03X285579Y1897826I4873J0D01*
G37*
G36*
G01X1008019Y157668D02*
G02X988042I-9989J-8073D01*
G03X989125Y160731I-3790J3063D01*
G01Y163376D01*
G02X1006936I8906J0D01*
G01Y160731D01*
G03X1008019Y157668I4873J0D01*
G37*
G36*
G01Y681290D02*
G02X988042I-9989J-8073D01*
G03X989125Y684353I-3790J3063D01*
G01Y686998D01*
G02X1006936I8906J0D01*
G01Y684353D01*
G03X1008019Y681290I4873J0D01*
G37*
G36*
G01Y1076959D02*
G02X988042I-9989J-8073D01*
G03X989125Y1080022I-3790J3063D01*
G01Y1082667D01*
G02X1006936I8906J0D01*
G01Y1080022D01*
G03X1008019Y1076959I4873J0D01*
G37*
G36*
G01Y1897826D02*
G02X988042I-9989J-8073D01*
G03X989125Y1900889I-3790J3063D01*
G01Y1903534D01*
G02X1006936I8906J0D01*
G01Y1900889D01*
G03X1008019Y1897826I4873J0D01*
G37*
G54D21*
X110000Y362500D03*
X106500D03*
X110000Y366000D03*
X106500D03*
Y771500D03*
X110000D03*
Y768000D03*
X106500D03*
X110000Y1173500D03*
X106500D03*
X110000Y1177000D03*
X106500D03*
X110500Y1573200D03*
X107000D03*
X103500D03*
X107000Y1576700D03*
X103500D03*
X110500D03*
X80400Y1957900D03*
X73400D03*
X76900D03*
X87500Y1954300D03*
X80400Y1954400D03*
X83900D03*
X73400D03*
X76900D03*
X117000Y362500D03*
Y366000D03*
X113500Y362500D03*
Y366000D03*
X117000Y771500D03*
Y768000D03*
X113500Y771500D03*
Y768000D03*
X117000Y1173500D03*
Y1177000D03*
X113500Y1173500D03*
Y1177000D03*
X114000Y1573200D03*
Y1576700D03*
X356257Y344176D03*
X391750Y344500D03*
X383750D03*
X348256Y344114D03*
X377250Y774500D03*
X385238Y774122D03*
X391758Y1145676D03*
X383757Y1145655D03*
X836500Y362500D03*
X833000D03*
X840000Y366000D03*
Y362500D03*
X833000Y366000D03*
X836500D03*
X840000Y771500D03*
X833000D03*
X836500D03*
X840000Y768000D03*
X836500D03*
X833000D03*
X836500Y1177000D03*
X833000D03*
X840000D03*
Y1582500D03*
X833000D03*
X836500D03*
X840000Y1579000D03*
X836500D03*
X833000D03*
X796339Y1937007D03*
Y1940507D03*
X804239Y1953307D03*
Y1956807D03*
X800739D03*
Y1953307D03*
X797239D03*
Y1956807D03*
X843500Y366000D03*
Y362500D03*
Y771500D03*
Y768000D03*
Y1177000D03*
Y1582500D03*
Y1579000D03*
G54D23*
X290580Y559000D03*
X298450D03*
X425890Y820729D03*
X425891Y812750D03*
X425500Y1215250D03*
Y1223250D03*
X881353Y1650749D03*
X877853D03*
Y1654249D03*
X881353D03*
%LPC*%
G75*
G54D25*
G01X-106883Y-224955D02*
Y-304955D01*
G01Y-260455D02*
X1019417D01*
G01X-106883Y-304955D02*
X1019417D01*
G01X-110883Y-208955D02*
G02I-12000J0D01*
G01X-116033D02*
G02I-6850J0D01*
G01X-122883Y-224955D02*
Y-192955D01*
G01X-106883Y-208955D02*
X-138883D01*
G01X-106883Y-224955D02*
X1019417D01*
G01X231917D02*
Y-304955D01*
G01X369417Y-224955D02*
Y-304955D01*
G01X484417Y-224955D02*
Y-304955D01*
G01X651917Y-224955D02*
Y-304955D01*
G01X821917Y-224955D02*
Y-304955D01*
G01X1019417Y-224955D02*
Y-304955D01*
G01X1047417Y-208955D02*
G02I-12000J0D01*
G01X1042267D02*
G02I-6850J0D01*
G01X1035417Y-224955D02*
Y-192955D01*
G01X1051417Y-208955D02*
X1019417D01*
G54D26*
G01X-90900Y-277455D02*
Y-294955D01*
X-82166D01*
G01X-69033Y-283289D02*
Y-294955D01*
G01Y-278622D02*
X-69470Y-278330D01*
Y-277747D01*
X-69033Y-277455D01*
X-68596Y-277747D01*
Y-278330D01*
X-69033Y-278622D01*
G01X-54590Y-299330D02*
X-53061Y-300497D01*
X-51315Y-300788D01*
X-49787Y-300497D01*
X-48476Y-299039D01*
X-47603Y-296997D01*
Y-283289D01*
G01Y-285622D02*
X-48476Y-284455D01*
X-49787Y-283580D01*
X-51315Y-283289D01*
X-53061Y-283872D01*
X-54153Y-285038D01*
X-55027Y-287080D01*
X-55463Y-289122D01*
X-55245Y-290872D01*
X-54371Y-292914D01*
X-53061Y-294372D01*
X-51315Y-294955D01*
X-50005Y-294663D01*
X-48476Y-293497D01*
X-47603Y-292331D01*
G01X-37745Y-294955D02*
Y-277455D01*
G01Y-285913D02*
X-36653Y-284455D01*
X-35561Y-283580D01*
X-33815Y-283289D01*
X-32505Y-283580D01*
X-30976Y-284747D01*
X-30321Y-286497D01*
Y-294955D01*
G01X-16533Y-277455D02*
Y-294955D01*
G01X-19590Y-283289D02*
X-13476D01*
G01X-2745Y-294955D02*
Y-283289D01*
G01Y-286205D02*
X-1871Y-284747D01*
X-561Y-283580D01*
X1185Y-283289D01*
X2713Y-283580D01*
X4024Y-284747D01*
X4679Y-286788D01*
Y-294955D01*
G01X18467Y-283289D02*
Y-294955D01*
G01Y-278622D02*
X18030Y-278330D01*
Y-277747D01*
X18467Y-277455D01*
X18904Y-277747D01*
Y-278330D01*
X18467Y-278622D01*
G01X32255Y-294955D02*
Y-283289D01*
G01Y-286205D02*
X33129Y-284747D01*
X34439Y-283580D01*
X36185Y-283289D01*
X37713Y-283580D01*
X39024Y-284747D01*
X39679Y-286788D01*
Y-294955D01*
G01X50410Y-299330D02*
X51939Y-300497D01*
X53685Y-300788D01*
X55213Y-300497D01*
X56524Y-299039D01*
X57397Y-296997D01*
Y-283289D01*
G01Y-285622D02*
X56524Y-284455D01*
X55213Y-283580D01*
X53685Y-283289D01*
X51939Y-283872D01*
X50847Y-285038D01*
X49973Y-287080D01*
X49537Y-289122D01*
X49755Y-290872D01*
X50629Y-292914D01*
X51939Y-294372D01*
X53685Y-294955D01*
X54995Y-294663D01*
X56524Y-293497D01*
X57397Y-292331D01*
G01X84100Y-294955D02*
Y-277455D01*
X89340D01*
X91087Y-278330D01*
X92397Y-280372D01*
X92834Y-282705D01*
X92397Y-285038D01*
X91305Y-286788D01*
X89340Y-287664D01*
X84100D01*
G01X101164Y-294955D02*
Y-277455D01*
X105530D01*
X107277Y-278330D01*
X108587Y-279497D01*
X109679Y-281246D01*
X110552Y-283289D01*
X110770Y-286205D01*
X110552Y-289122D01*
X109679Y-291164D01*
X108587Y-292914D01*
X107277Y-294080D01*
X105530Y-294955D01*
X101164D01*
G01X119100D02*
Y-277455D01*
X124340D01*
X126087Y-278330D01*
X127397Y-280372D01*
X127834Y-282705D01*
X127397Y-285038D01*
X126305Y-286788D01*
X124340Y-287664D01*
X119100D01*
G01X142713Y-285622D02*
X143587Y-284747D01*
X144242Y-283289D01*
X144679Y-281246D01*
X144242Y-279497D01*
X143369Y-278330D01*
X141840Y-277455D01*
X135945D01*
Y-294955D01*
X143150D01*
X144679Y-293789D01*
X145552Y-292038D01*
X145989Y-289997D01*
X145552Y-287955D01*
X144242Y-286205D01*
X142713Y-285622D01*
X135945D01*
G01X171600Y-294955D02*
Y-277455D01*
X176840D01*
X178587Y-278330D01*
X179897Y-280372D01*
X180334Y-282705D01*
X179897Y-285038D01*
X178805Y-286788D01*
X176840Y-287664D01*
X171600D01*
G01X188008Y-277455D02*
X193467Y-294955D01*
X198926Y-277455D01*
G01X210967D02*
Y-294955D01*
G01X205945Y-277455D02*
X215989D01*
G01X21540Y-249955D02*
Y-232455D01*
X27217Y-247038D01*
X32894Y-232455D01*
Y-249955D01*
G01X44717D02*
X43407Y-249663D01*
X42097Y-248497D01*
X41223Y-246455D01*
X40787Y-244122D01*
X41223Y-241788D01*
X42097Y-239747D01*
X43407Y-238580D01*
X44717Y-238289D01*
X46027Y-238580D01*
X47337Y-239747D01*
X48210Y-241788D01*
X48429Y-244122D01*
X48210Y-246455D01*
X47337Y-248497D01*
X46027Y-249663D01*
X44717Y-249955D01*
G01X66147Y-232455D02*
Y-249955D01*
G01Y-247331D02*
X65274Y-248789D01*
X63963Y-249663D01*
X62435Y-249955D01*
X60689Y-249372D01*
X59379Y-247914D01*
X58505Y-246164D01*
X58287Y-244122D01*
X58505Y-242080D01*
X59379Y-240330D01*
X60689Y-238872D01*
X62435Y-238289D01*
X63963Y-238580D01*
X65055Y-239164D01*
X66147Y-240330D01*
G01X76442Y-242080D02*
X83429D01*
X82774Y-240038D01*
X81682Y-238872D01*
X80154Y-238289D01*
X78625Y-238580D01*
X77315Y-239455D01*
X76442Y-241497D01*
X76005Y-243247D01*
Y-244997D01*
X76442Y-246747D01*
X77534Y-248497D01*
X78844Y-249663D01*
X80372Y-249955D01*
X81900Y-249372D01*
X83429Y-247622D01*
G01X97217Y-249955D02*
Y-232455D01*
G01X252500Y-249955D02*
Y-232455D01*
X257740D01*
X259487Y-233330D01*
X260797Y-235372D01*
X261234Y-237705D01*
X260797Y-240038D01*
X259705Y-241788D01*
X257740Y-242664D01*
X252500D01*
G01X279170Y-233914D02*
X277860Y-233038D01*
X276332Y-232455D01*
X274585D01*
X272620Y-233330D01*
X271092Y-234788D01*
X270000Y-236539D01*
X269127Y-239455D01*
X268908Y-242080D01*
X269345Y-244705D01*
X270000Y-246455D01*
X271310Y-248205D01*
X272839Y-249372D01*
X274367Y-249955D01*
X275895D01*
X277424Y-249372D01*
X278734Y-248497D01*
X279826Y-247331D01*
G01X293613Y-240622D02*
X294487Y-239747D01*
X295142Y-238289D01*
X295579Y-236246D01*
X295142Y-234497D01*
X294269Y-233330D01*
X292740Y-232455D01*
X286845D01*
Y-249955D01*
X294050D01*
X295579Y-248789D01*
X296452Y-247038D01*
X296889Y-244997D01*
X296452Y-242955D01*
X295142Y-241205D01*
X293613Y-240622D01*
X286845D01*
G01X302817Y-255788D02*
X315917D01*
G01X321845Y-249955D02*
Y-232455D01*
X331889Y-249955D01*
Y-232455D01*
G01X344367Y-249955D02*
X342620Y-249663D01*
X341092Y-248497D01*
X339782Y-246747D01*
X338908Y-244705D01*
X338472Y-242372D01*
Y-240038D01*
X338908Y-237705D01*
X339782Y-235663D01*
X341092Y-233914D01*
X342620Y-232747D01*
X344367Y-232455D01*
X346113Y-232747D01*
X347642Y-233914D01*
X348952Y-235663D01*
X349826Y-237705D01*
X350262Y-240038D01*
Y-242372D01*
X349826Y-244705D01*
X348952Y-246747D01*
X347642Y-248497D01*
X346113Y-249663D01*
X344367Y-249955D01*
G01X265617Y-294955D02*
Y-277455D01*
X262997Y-280955D01*
G01Y-294955D02*
X268237D01*
G01X278314Y-292331D02*
X279623Y-293789D01*
X281152Y-294663D01*
X283117Y-294955D01*
X285082Y-294372D01*
X286610Y-293205D01*
X287702Y-291164D01*
X287920Y-288830D01*
X287484Y-286497D01*
X286392Y-285038D01*
X284863Y-283872D01*
X283335Y-283580D01*
X281807Y-283872D01*
X279842Y-285038D01*
X280497Y-277455D01*
X286392D01*
G01X296469Y-287664D02*
X297997Y-285622D01*
X299307Y-284455D01*
X301054Y-283872D01*
X302582Y-284455D01*
X303674Y-285622D01*
X304547Y-287372D01*
X304765Y-289413D01*
X304547Y-291164D01*
X303674Y-292914D01*
X302363Y-294372D01*
X300835Y-294955D01*
X299089Y-294372D01*
X297560Y-292622D01*
X296687Y-289997D01*
X296469Y-287080D01*
X296905Y-283289D01*
X297560Y-281246D01*
X298652Y-279205D01*
X300180Y-277747D01*
X301709Y-277455D01*
X303237Y-278038D01*
X304329Y-279497D01*
G01X313969Y-287664D02*
X315497Y-285622D01*
X316807Y-284455D01*
X318554Y-283872D01*
X320082Y-284455D01*
X321174Y-285622D01*
X322047Y-287372D01*
X322265Y-289413D01*
X322047Y-291164D01*
X321174Y-292914D01*
X319863Y-294372D01*
X318335Y-294955D01*
X316589Y-294372D01*
X315060Y-292622D01*
X314187Y-289997D01*
X313969Y-287080D01*
X314405Y-283289D01*
X315060Y-281246D01*
X316152Y-279205D01*
X317680Y-277747D01*
X319209Y-277455D01*
X320737Y-278038D01*
X321829Y-279497D01*
G01X331905Y-292914D02*
X333434Y-294372D01*
X335180Y-294955D01*
X336927Y-294372D01*
X338455Y-292622D01*
X339547Y-289997D01*
X339984Y-287372D01*
Y-284164D01*
X339547Y-281539D01*
X338455Y-279205D01*
X337145Y-278038D01*
X335617Y-277455D01*
X333870Y-278038D01*
X332560Y-279205D01*
X331687Y-280955D01*
X331250Y-283289D01*
X331687Y-285330D01*
X332779Y-287372D01*
X334089Y-288539D01*
X335617Y-288830D01*
X337363Y-288247D01*
X338674Y-286788D01*
X339984Y-284164D01*
G01X395208Y-232455D02*
X400667Y-249955D01*
X406126Y-232455D01*
G01X422534Y-249955D02*
X413800D01*
Y-232455D01*
X422534D01*
G01X419040Y-240913D02*
X413800D01*
G01X431300Y-249955D02*
Y-232455D01*
X436759D01*
X438505Y-233330D01*
X439597Y-234497D01*
X440034Y-236830D01*
X439597Y-239164D01*
X438287Y-240622D01*
X436759Y-241497D01*
X431300D01*
G01X436759D02*
X440034Y-249955D01*
G01X453167Y-250538D02*
X452730Y-250247D01*
Y-249663D01*
X453167Y-249372D01*
X453604Y-249663D01*
Y-250247D01*
X453167Y-250538D01*
G01X426917Y-294955D02*
Y-277455D01*
X424297Y-280955D01*
G01Y-294955D02*
X429537D01*
G01X528750Y-232455D02*
Y-249955D01*
X537484D01*
G01X554547D02*
Y-238289D01*
G01Y-240330D02*
X553674Y-239164D01*
X552363Y-238580D01*
X550835Y-238289D01*
X549307Y-238872D01*
X547997Y-240038D01*
X547123Y-241788D01*
X546687Y-244122D01*
X547123Y-246455D01*
X547997Y-248205D01*
X549307Y-249372D01*
X550835Y-249955D01*
X552363Y-249663D01*
X553674Y-248789D01*
X554547Y-247622D01*
G01X563532Y-255205D02*
X564842Y-255788D01*
X566589Y-255205D01*
X567680Y-254039D01*
X568554Y-252580D01*
X569863Y-247914D01*
X572702Y-238289D01*
G01X565715D02*
X569863Y-247914D01*
G01X582342Y-242080D02*
X589329D01*
X588674Y-240038D01*
X587582Y-238872D01*
X586054Y-238289D01*
X584525Y-238580D01*
X583215Y-239455D01*
X582342Y-241497D01*
X581905Y-243247D01*
Y-244997D01*
X582342Y-246747D01*
X583434Y-248497D01*
X584744Y-249663D01*
X586272Y-249955D01*
X587800Y-249372D01*
X589329Y-247622D01*
G01X600060Y-249955D02*
Y-238289D01*
G01Y-240622D02*
X601152Y-239455D01*
X602244Y-238580D01*
X603772Y-238289D01*
X604863Y-238580D01*
X606174Y-239455D01*
G01X607484Y-277455D02*
Y-294955D01*
X598750D01*
G01X590420Y-292331D02*
X589111Y-293789D01*
X587582Y-294663D01*
X585617Y-294955D01*
X583652Y-294372D01*
X582124Y-293205D01*
X581032Y-291164D01*
X580814Y-288830D01*
X581250Y-286497D01*
X582342Y-285038D01*
X583871Y-283872D01*
X585399Y-283580D01*
X586927Y-283872D01*
X588892Y-285038D01*
X588237Y-277455D01*
X582342D01*
G01X573576D02*
X568117Y-294955D01*
X562658Y-277455D01*
G01X545814Y-278914D02*
X547124Y-278038D01*
X548652Y-277455D01*
X550399D01*
X552364Y-278330D01*
X553892Y-279788D01*
X554984Y-281539D01*
X555857Y-284455D01*
X556076Y-287080D01*
X555639Y-289705D01*
X554984Y-291455D01*
X553674Y-293205D01*
X552145Y-294372D01*
X550617Y-294955D01*
X549089D01*
X547560Y-294372D01*
X546250Y-293497D01*
X545158Y-292331D01*
G01X528314Y-278914D02*
X529624Y-278038D01*
X531152Y-277455D01*
X532899D01*
X534864Y-278330D01*
X536392Y-279788D01*
X537484Y-281539D01*
X538357Y-284455D01*
X538576Y-287080D01*
X538139Y-289705D01*
X537484Y-291455D01*
X536174Y-293205D01*
X534645Y-294372D01*
X533117Y-294955D01*
X531589D01*
X530060Y-294372D01*
X528750Y-293497D01*
X527658Y-292331D01*
G01X670864Y-249955D02*
Y-232455D01*
X675230D01*
X676977Y-233330D01*
X678287Y-234497D01*
X679379Y-236246D01*
X680252Y-238289D01*
X680470Y-241205D01*
X680252Y-244122D01*
X679379Y-246164D01*
X678287Y-247914D01*
X676977Y-249080D01*
X675230Y-249955D01*
X670864D01*
G01X689892Y-242080D02*
X696879D01*
X696224Y-240038D01*
X695132Y-238872D01*
X693604Y-238289D01*
X692075Y-238580D01*
X690765Y-239455D01*
X689892Y-241497D01*
X689455Y-243247D01*
Y-244997D01*
X689892Y-246747D01*
X690984Y-248497D01*
X692294Y-249663D01*
X693822Y-249955D01*
X695350Y-249372D01*
X696879Y-247622D01*
G01X707392Y-247914D02*
X708484Y-249080D01*
X710012Y-249955D01*
X711322D01*
X712632Y-249372D01*
X713505Y-248497D01*
X713942Y-247331D01*
X713724Y-245580D01*
X712850Y-244705D01*
X708920Y-242955D01*
X708047Y-240913D01*
X708484Y-239455D01*
X709357Y-238580D01*
X710667Y-238289D01*
X711977Y-238580D01*
X713287Y-239455D01*
G01X728167Y-238289D02*
Y-249955D01*
G01Y-233622D02*
X727730Y-233330D01*
Y-232747D01*
X728167Y-232455D01*
X728604Y-232747D01*
Y-233330D01*
X728167Y-233622D01*
G01X742610Y-254330D02*
X744139Y-255497D01*
X745885Y-255788D01*
X747413Y-255497D01*
X748724Y-254039D01*
X749597Y-251997D01*
Y-238289D01*
G01Y-240622D02*
X748724Y-239455D01*
X747413Y-238580D01*
X745885Y-238289D01*
X744139Y-238872D01*
X743047Y-240038D01*
X742173Y-242080D01*
X741737Y-244122D01*
X741955Y-245872D01*
X742829Y-247914D01*
X744139Y-249372D01*
X745885Y-249955D01*
X747195Y-249663D01*
X748724Y-248497D01*
X749597Y-247331D01*
G01X759455Y-249955D02*
Y-238289D01*
G01Y-241205D02*
X760329Y-239747D01*
X761639Y-238580D01*
X763385Y-238289D01*
X764913Y-238580D01*
X766224Y-239747D01*
X766879Y-241788D01*
Y-249955D01*
G01X777392Y-242080D02*
X784379D01*
X783724Y-240038D01*
X782632Y-238872D01*
X781104Y-238289D01*
X779575Y-238580D01*
X778265Y-239455D01*
X777392Y-241497D01*
X776955Y-243247D01*
Y-244997D01*
X777392Y-246747D01*
X778484Y-248497D01*
X779794Y-249663D01*
X781322Y-249955D01*
X782850Y-249372D01*
X784379Y-247622D01*
G01X795110Y-249955D02*
Y-238289D01*
G01Y-240622D02*
X796202Y-239455D01*
X797294Y-238580D01*
X798822Y-238289D01*
X799913Y-238580D01*
X801224Y-239455D01*
G01X660367Y-277455D02*
X663423Y-294955D01*
X666917Y-277455D01*
X670410Y-294955D01*
X673467Y-277455D01*
G01X680050Y-294955D02*
Y-277455D01*
X685290D01*
X687037Y-278330D01*
X688347Y-280372D01*
X688784Y-282705D01*
X688347Y-285038D01*
X687255Y-286788D01*
X685290Y-287664D01*
X680050D01*
G01X697332Y-294955D02*
Y-277455D01*
G01X706502D02*
Y-294955D01*
G01Y-286205D02*
X697332D01*
G01X716579Y-289122D02*
X722255D01*
G01X732769Y-294955D02*
Y-277455D01*
X741065D01*
G01X738009Y-285913D02*
X732769D01*
G01X750050Y-277455D02*
Y-294955D01*
X758784D01*
G01X771917D02*
X770170Y-294663D01*
X768642Y-293497D01*
X767332Y-291747D01*
X766458Y-289705D01*
X766022Y-287372D01*
Y-285038D01*
X766458Y-282705D01*
X767332Y-280663D01*
X768642Y-278914D01*
X770170Y-277747D01*
X771917Y-277455D01*
X773663Y-277747D01*
X775192Y-278914D01*
X776502Y-280663D01*
X777376Y-282705D01*
X777812Y-285038D01*
Y-287372D01*
X777376Y-289705D01*
X776502Y-291747D01*
X775192Y-293497D01*
X773663Y-294663D01*
X771917Y-294955D01*
G01X785050D02*
Y-277455D01*
X790509D01*
X792255Y-278330D01*
X793347Y-279497D01*
X793784Y-281830D01*
X793347Y-284164D01*
X792037Y-285622D01*
X790509Y-286497D01*
X785050D01*
G01X790509D02*
X793784Y-294955D01*
G01X801458D02*
X806917Y-277455D01*
X812376Y-294955D01*
G01X810410Y-288830D02*
X803423D01*
G01X841867Y-294955D02*
Y-277455D01*
X839247Y-280955D01*
G01Y-294955D02*
X844487D01*
G01X859367D02*
Y-277455D01*
X856747Y-280955D01*
G01Y-294955D02*
X861987D01*
G01X872937Y-295538D02*
X880797Y-277455D01*
G01X894367Y-294955D02*
Y-277455D01*
X891747Y-280955D01*
G01Y-294955D02*
X896987D01*
G01X907719Y-287664D02*
X909247Y-285622D01*
X910557Y-284455D01*
X912304Y-283872D01*
X913832Y-284455D01*
X914924Y-285622D01*
X915797Y-287372D01*
X916015Y-289413D01*
X915797Y-291164D01*
X914924Y-292914D01*
X913613Y-294372D01*
X912085Y-294955D01*
X910339Y-294372D01*
X908810Y-292622D01*
X907937Y-289997D01*
X907719Y-287080D01*
X908155Y-283289D01*
X908810Y-281246D01*
X909902Y-279205D01*
X911430Y-277747D01*
X912959Y-277455D01*
X914487Y-278038D01*
X915579Y-279497D01*
G01X925437Y-295538D02*
X933297Y-277455D01*
G01X942719Y-280372D02*
X944029Y-278622D01*
X945557Y-277747D01*
X947304Y-277455D01*
X949487Y-278038D01*
X951015Y-279497D01*
X951452Y-281246D01*
X951234Y-282997D01*
X950360Y-284455D01*
X945994Y-287372D01*
X944029Y-289413D01*
X942719Y-292331D01*
X942282Y-294955D01*
X951452D01*
G01X964367Y-277455D02*
X962620Y-278038D01*
X961310Y-279497D01*
X960437Y-281246D01*
X959782Y-283580D01*
X959564Y-286205D01*
X959782Y-288830D01*
X960437Y-291164D01*
X961310Y-292914D01*
X962620Y-294372D01*
X964367Y-294955D01*
X966113Y-294372D01*
X967424Y-292914D01*
X968297Y-291164D01*
X968952Y-288830D01*
X969170Y-286205D01*
X968952Y-283580D01*
X968297Y-281246D01*
X967424Y-279497D01*
X966113Y-278038D01*
X964367Y-277455D01*
G01X981867Y-294955D02*
Y-277455D01*
X979247Y-280955D01*
G01Y-294955D02*
X984487D01*
G01X995219Y-287664D02*
X996747Y-285622D01*
X998057Y-284455D01*
X999804Y-283872D01*
X1001332Y-284455D01*
X1002424Y-285622D01*
X1003297Y-287372D01*
X1003515Y-289413D01*
X1003297Y-291164D01*
X1002424Y-292914D01*
X1001113Y-294372D01*
X999585Y-294955D01*
X997839Y-294372D01*
X996310Y-292622D01*
X995437Y-289997D01*
X995219Y-287080D01*
X995655Y-283289D01*
X996310Y-281246D01*
X997402Y-279205D01*
X998930Y-277747D01*
X1000459Y-277455D01*
X1001987Y-278038D01*
X1003079Y-279497D01*
G01X889564Y-249955D02*
Y-232455D01*
X893930D01*
X895677Y-233330D01*
X896987Y-234497D01*
X898079Y-236246D01*
X898952Y-238289D01*
X899170Y-241205D01*
X898952Y-244122D01*
X898079Y-246164D01*
X896987Y-247914D01*
X895677Y-249080D01*
X893930Y-249955D01*
X889564D01*
G01X915797D02*
Y-238289D01*
G01Y-240330D02*
X914924Y-239164D01*
X913613Y-238580D01*
X912085Y-238289D01*
X910557Y-238872D01*
X909247Y-240038D01*
X908373Y-241788D01*
X907937Y-244122D01*
X908373Y-246455D01*
X909247Y-248205D01*
X910557Y-249372D01*
X912085Y-249955D01*
X913613Y-249663D01*
X914924Y-248789D01*
X915797Y-247622D01*
G01X929367Y-232455D02*
Y-249955D01*
G01X926310Y-238289D02*
X932424D01*
G01X943592Y-242080D02*
X950579D01*
X949924Y-240038D01*
X948832Y-238872D01*
X947304Y-238289D01*
X945775Y-238580D01*
X944465Y-239455D01*
X943592Y-241497D01*
X943155Y-243247D01*
Y-244997D01*
X943592Y-246747D01*
X944684Y-248497D01*
X945994Y-249663D01*
X947522Y-249955D01*
X949050Y-249372D01*
X950579Y-247622D01*
M02*
